FILE_TYPE = MACRO_DRAWING;
SET COLOR_WIRE YELLOW;
SET COLOR_PROP MONO;
SET COLOR_DOT WHITE;
SET COLOR_ARC YELLOW;
SET COLOR_BODY GREEN;
SET COLOR_NOTE MONO;
SET PROP_DISPLAY VALUE;
SET PAGE_NUMBER P193;
FORCEADD VCC_CORE..1
(-3800 4700);
FORCEPROP 3 LASTPIN (-3800 4650) SIG_NAME PVCCMCP_CPU1\g
J 0
(-3790 4660);
DISPLAY 0.659574 (-3790 4660);
PAINT MONO (-3790 4660);
DISPLAY INVISIBLE (-3790 4660);
FORCEPROP 1 LAST HDL_POWER PVCCMCP_CPU1
J 1
(-3800 4750);
DISPLAY 0.617021 (-3800 4750);
PAINT GREEN (-3800 4750);
FORCEPROP 1 LAST PATH I107
J 0
(-3750 4725);
DISPLAY 0.872340 (-3750 4725);
PAINT AQUA (-3750 4725);
DISPLAY INVISIBLE (-3750 4725);
FORCEPROP 2 LAST CDS_LIB mstr_symbols
J 0
(-3800 4700);
PAINT MONO (-3800 4700);
DISPLAY INVISIBLE (-3800 4700);
FORCEADD OFFPAGE..4
(-5050 2675);
FORCEPROP 2 LAST $XR0 190 
J 0
(-4864 2675);
DISPLAY 0.638298 (-4864 2675);
PAINT MONO (-4864 2675);
FORCEPROP 2 LAST CDS_LIB mstr_standard
J 0
(-5050 2675);
PAINT MONO (-5050 2675);
DISPLAY INVISIBLE (-5050 2675);
FORCEPROP 2 LAST ROOM P0V95_FPGA_CPU0_VR
J 0
(-5600 2750);
DISPLAY 1.361702 (-5600 2750);
PAINT ORANGE (-5600 2750);
DISPLAY INVISIBLE (-5600 2750);
FORCEPROP 2 LAST PATH I111
J 0
(-4850 2725);
DISPLAY 1.021277 (-4850 2725);
PAINT ORANGE (-4850 2725);
DISPLAY INVISIBLE (-4850 2725);
FORCEPROP 1 LAST OFFPAGE TRUE
J 0
(-4725 2550);
DISPLAY 0.872340 (-4725 2550);
PAINT GREEN (-4725 2550);
DISPLAY INVISIBLE (-4725 2550);
FORCEPROP 1 LAST COMMENT_BODY TRUE
J 0
(-5075 2575);
DISPLAY 0.872340 (-5075 2575);
PAINT GREEN (-5075 2575);
DISPLAY INVISIBLE (-5075 2575);
FORCEADD OFFPAGE..2
(-5025 2625);
FORCEPROP 2 LAST $XR0 190 
J 0
(-4836 2625);
DISPLAY 0.638298 (-4836 2625);
PAINT MONO (-4836 2625);
FORCEPROP 2 LAST CDS_LIB mstr_standard
J 0
(-5025 2625);
PAINT MONO (-5025 2625);
DISPLAY INVISIBLE (-5025 2625);
FORCEPROP 2 LAST ROOM P0V95_FPGA_CPU0_VR
J 0
(-5450 2700);
DISPLAY 1.361702 (-5450 2700);
PAINT ORANGE (-5450 2700);
DISPLAY INVISIBLE (-5450 2700);
FORCEPROP 2 LAST PATH I112
J 0
(-4825 2675);
DISPLAY 1.021277 (-4825 2675);
PAINT ORANGE (-4825 2675);
DISPLAY INVISIBLE (-4825 2675);
FORCEPROP 1 LAST OFFPAGE TRUE
J 0
(-4700 2500);
DISPLAY 1.170213 (-4700 2500);
PAINT GREEN (-4700 2500);
DISPLAY INVISIBLE (-4700 2500);
FORCEPROP 1 LAST COMMENT_BODY TRUE
J 0
(-5070 2530);
DISPLAY 1.170213 (-5070 2530);
PAINT GREEN (-5070 2530);
DISPLAY INVISIBLE (-5070 2530);
FORCEADD OFFPAGE..4
(-5100 3025);
FORCEPROP 2 LAST $XR0 191 
J 0
(-4914 3025);
DISPLAY 0.638298 (-4914 3025);
PAINT MONO (-4914 3025);
FORCEPROP 2 LAST PATH I113
J 0
(-4900 3075);
DISPLAY 1.021277 (-4900 3075);
PAINT ORANGE (-4900 3075);
DISPLAY INVISIBLE (-4900 3075);
FORCEPROP 2 LAST ROOM P0V95_FPGA_CPU0_VR
J 0
(-5650 3100);
DISPLAY 1.361702 (-5650 3100);
PAINT ORANGE (-5650 3100);
DISPLAY INVISIBLE (-5650 3100);
FORCEPROP 2 LAST CDS_LIB mstr_standard
J 0
(-5100 3025);
PAINT MONO (-5100 3025);
DISPLAY INVISIBLE (-5100 3025);
FORCEPROP 1 LAST OFFPAGE TRUE
J 0
(-4775 2900);
DISPLAY 0.872340 (-4775 2900);
PAINT GREEN (-4775 2900);
DISPLAY INVISIBLE (-4775 2900);
FORCEPROP 1 LAST COMMENT_BODY TRUE
J 0
(-5125 2925);
DISPLAY 0.872340 (-5125 2925);
PAINT GREEN (-5125 2925);
DISPLAY INVISIBLE (-5125 2925);
FORCEADD OFFPAGE..2
(-5075 2975);
FORCEPROP 2 LAST $XR0 191 
J 0
(-4886 2975);
DISPLAY 0.638298 (-4886 2975);
PAINT MONO (-4886 2975);
FORCEPROP 2 LAST PATH I114
J 0
(-4875 3025);
DISPLAY 1.021277 (-4875 3025);
PAINT ORANGE (-4875 3025);
DISPLAY INVISIBLE (-4875 3025);
FORCEPROP 2 LAST ROOM P0V95_FPGA_CPU0_VR
J 0
(-5500 3050);
DISPLAY 1.361702 (-5500 3050);
PAINT ORANGE (-5500 3050);
DISPLAY INVISIBLE (-5500 3050);
FORCEPROP 2 LAST CDS_LIB mstr_standard
J 0
(-5075 2975);
PAINT MONO (-5075 2975);
DISPLAY INVISIBLE (-5075 2975);
FORCEPROP 1 LAST OFFPAGE TRUE
J 0
(-4750 2850);
DISPLAY 1.170213 (-4750 2850);
PAINT GREEN (-4750 2850);
DISPLAY INVISIBLE (-4750 2850);
FORCEPROP 1 LAST COMMENT_BODY TRUE
J 0
(-5120 2880);
DISPLAY 1.170213 (-5120 2880);
PAINT GREEN (-5120 2880);
DISPLAY INVISIBLE (-5120 2880);
FORCEADD VCC_CORE..1
(-4050 4650);
FORCEPROP 3 LASTPIN (-4050 4600) SIG_NAME P1V8_MCP_CPU1\g
J 0
(-4040 4610);
DISPLAY 0.659574 (-4040 4610);
PAINT MONO (-4040 4610);
DISPLAY INVISIBLE (-4040 4610);
FORCEPROP 1 LAST HDL_POWER P1V8_MCP_CPU1
J 1
(-4050 4700);
DISPLAY 0.617021 (-4050 4700);
PAINT GREEN (-4050 4700);
FORCEPROP 1 LAST PATH I131
J 0
(-4000 4675);
DISPLAY 0.872340 (-4000 4675);
PAINT AQUA (-4000 4675);
DISPLAY INVISIBLE (-4000 4675);
FORCEPROP 2 LAST CDS_LIB mstr_symbols
J 0
(-4050 4650);
PAINT ORANGE (-4050 4650);
DISPLAY INVISIBLE (-4050 4650);
FORCEPROP 0 LAST VOLTAGE 1.8
J 0
(-4050 4800);
DISPLAY 1.021277 (-4050 4800);
PAINT SKYBLUE (-4050 4800);
DISPLAY INVISIBLE (-4050 4800);
FORCEADD VCC_CORE..1
(-5250 3225);
FORCEPROP 3 LASTPIN (-5250 3175) SIG_NAME PVCCIOMCP_CPU1\g
J 0
(-5240 3185);
DISPLAY 0.659574 (-5240 3185);
PAINT MONO (-5240 3185);
DISPLAY INVISIBLE (-5240 3185);
FORCEPROP 1 LAST HDL_POWER PVCCIOMCP_CPU1
J 1
(-5250 3275);
DISPLAY 0.617021 (-5250 3275);
PAINT GREEN (-5250 3275);
FORCEPROP 1 LAST PATH I134
J 0
(-5200 3250);
DISPLAY 0.872340 (-5200 3250);
PAINT AQUA (-5200 3250);
DISPLAY INVISIBLE (-5200 3250);
FORCEPROP 2 LAST CDS_LIB mstr_symbols
J 0
(-5250 3225);
PAINT ORANGE (-5250 3225);
DISPLAY INVISIBLE (-5250 3225);
FORCEPROP 0 LAST VOLTAGE +0.95
J 0
(-5250 3375);
DISPLAY 1.021277 (-5250 3375);
PAINT SKYBLUE (-5250 3375);
DISPLAY INVISIBLE (-5250 3375);
FORCEADD OFFPAGE..2
(-5150 1625);
FORCEPROP 2 LAST $XR2 55 
J 0
(-4721 1625);
DISPLAY 0.638298 (-4721 1625);
PAINT MONO (-4721 1625);
FORCEPROP 2 LAST $XR1 213 
J 0
(-4841 1625);
DISPLAY 0.638298 (-4841 1625);
PAINT MONO (-4841 1625);
FORCEPROP 2 LAST $XR0 206 
J 0
(-4961 1625);
DISPLAY 0.638298 (-4961 1625);
PAINT MONO (-4961 1625);
FORCEPROP 2 LAST PATH I138
J 0
(-4550 1675);
DISPLAY 1.021277 (-4550 1675);
PAINT ORANGE (-4550 1675);
DISPLAY INVISIBLE (-4550 1675);
FORCEPROP 2 LAST ROOM P0V95_FPGA_CPU0_VR
J 0
(-5575 1700);
DISPLAY 1.361702 (-5575 1700);
PAINT ORANGE (-5575 1700);
DISPLAY INVISIBLE (-5575 1700);
FORCEPROP 2 LAST CDS_LIB mstr_standard
J 0
(-5150 1625);
PAINT ORANGE (-5150 1625);
DISPLAY INVISIBLE (-5150 1625);
FORCEPROP 1 LAST OFFPAGE TRUE
J 0
(-4825 1500);
DISPLAY 1.170213 (-4825 1500);
PAINT GREEN (-4825 1500);
DISPLAY INVISIBLE (-4825 1500);
FORCEPROP 1 LAST COMMENT_BODY TRUE
J 0
(-5195 1530);
DISPLAY 1.170213 (-5195 1530);
PAINT GREEN (-5195 1530);
DISPLAY INVISIBLE (-5195 1530);
FORCEADD CAP_A..1
(-1900 2450);
FORCEPROP 1 LASTPIN (-1900 2350) $PN 2
J 0
(-1890 2330);
DISPLAY 0.617021 (-1890 2330);
PAINT ORANGE (-1890 2330);
FORCEPROP 1 LASTPIN (-1900 2550) $PN 1
J 0
(-1890 2530);
DISPLAY 0.617021 (-1890 2530);
PAINT ORANGE (-1890 2530);
FORCEPROP 1 LAST MATERIAL X5R
J 0
(-1850 2350);
DISPLAY 0.617021 (-1850 2350);
PAINT SKYBLUE (-1850 2350);
FORCEPROP 1 LAST VOLTAGE 4V
J 0
(-1850 2450);
DISPLAY 0.617021 (-1850 2450);
PAINT SKYBLUE (-1850 2450);
FORCEPROP 1 LAST TOLERANCE 20%
J 0
(-1850 2400);
DISPLAY 0.617021 (-1850 2400);
PAINT SKYBLUE (-1850 2400);
FORCEPROP 1 LAST VALUE 47UF
J 0
(-1850 2500);
DISPLAY 0.617021 (-1850 2500);
PAINT SKYBLUE (-1850 2500);
FORCEPROP 1 LAST LOCATION C3F1
J 0
(-1850 2550);
DISPLAY 0.617021 (-1850 2550);
PAINT AQUA (-1850 2550);
FORCEPROP 1 LAST PART_NUMBER 602433-106
J 0
(-1850 2300);
DISPLAY 0.617021 (-1850 2300);
PAINT BLUE (-1850 2300);
FORCEPROP 1 LAST PACK_TYPE 0603V
J 0
(-1850 2250);
DISPLAY 0.617021 (-1850 2250);
PAINT SKYBLUE (-1850 2250);
FORCEPROP 0 LAST GROUP PWR_MCP_CAP
J 0
(-1860 2201);
DISPLAY 0.638298 (-1860 2201);
PAINT BROWN (-1860 2201);
DISPLAY BOTH (-1860 2201);
FORCEPROP 1 LAST PATH I140
J 0
(-1850 2600);
DISPLAY 0.978723 (-1850 2600);
PAINT WHITE (-1850 2600);
DISPLAY INVISIBLE (-1850 2600);
FORCEPROP 2 LAST SEC 1
J 0
(-1850 2650);
PAINT MONO (-1850 2650);
DISPLAY INVISIBLE (-1850 2650);
FORCEPROP 2 LAST SEC_TYPE 0603V
J 0
(-1850 2650);
DISPLAY 1.021277 (-1850 2650);
PAINT ORANGE (-1850 2650);
DISPLAY INVISIBLE (-1850 2650);
FORCEPROP 2 LAST CDS_SEC 1
J 0
(-1850 2600);
PAINT ORANGE (-1850 2600);
DISPLAY INVISIBLE (-1850 2600);
FORCEPROP 2 LAST CDS_LIB dev_discrete
J 0
(-1900 2450);
PAINT ORANGE (-1900 2450);
DISPLAY INVISIBLE (-1900 2450);
FORCEPROP 2 LAST CDS_LOCATION C3F1
J 0
(-1850 2550);
DISPLAY 0.617021 (-1850 2550);
PAINT AQUA (-1850 2550);
DISPLAY INVISIBLE (-1850 2550);
FORCEADD CAP_A..1
(-1600 2450);
FORCEPROP 1 LASTPIN (-1600 2550) $PN 1
J 0
(-1590 2530);
DISPLAY 0.617021 (-1590 2530);
PAINT ORANGE (-1590 2530);
FORCEPROP 1 LASTPIN (-1600 2350) $PN 2
J 0
(-1590 2330);
DISPLAY 0.617021 (-1590 2330);
PAINT ORANGE (-1590 2330);
FORCEPROP 1 LAST LOCATION C4F2
J 0
(-1550 2550);
DISPLAY 0.617021 (-1550 2550);
PAINT AQUA (-1550 2550);
FORCEPROP 1 LAST PACK_TYPE 0603V
J 0
(-1550 2250);
DISPLAY 0.617021 (-1550 2250);
PAINT SKYBLUE (-1550 2250);
FORCEPROP 1 LAST PART_NUMBER 602433-106
J 0
(-1550 2300);
DISPLAY 0.617021 (-1550 2300);
PAINT BLUE (-1550 2300);
FORCEPROP 1 LAST MATERIAL X5R
J 0
(-1550 2350);
DISPLAY 0.617021 (-1550 2350);
PAINT SKYBLUE (-1550 2350);
FORCEPROP 1 LAST TOLERANCE 20%
J 0
(-1550 2400);
DISPLAY 0.617021 (-1550 2400);
PAINT SKYBLUE (-1550 2400);
FORCEPROP 1 LAST VOLTAGE 4V
J 0
(-1550 2450);
DISPLAY 0.617021 (-1550 2450);
PAINT SKYBLUE (-1550 2450);
FORCEPROP 1 LAST VALUE 47UF
J 0
(-1550 2500);
DISPLAY 0.617021 (-1550 2500);
PAINT SKYBLUE (-1550 2500);
FORCEPROP 0 LAST GROUP PWR_MCP_CAP
J 0
(-1560 2151);
DISPLAY 0.638298 (-1560 2151);
PAINT BROWN (-1560 2151);
DISPLAY BOTH (-1560 2151);
FORCEPROP 2 LAST CDS_LOCATION C4F2
J 0
(-1550 2550);
DISPLAY 0.617021 (-1550 2550);
PAINT AQUA (-1550 2550);
DISPLAY INVISIBLE (-1550 2550);
FORCEPROP 2 LAST CDS_LIB dev_discrete
J 0
(-1600 2450);
PAINT ORANGE (-1600 2450);
DISPLAY INVISIBLE (-1600 2450);
FORCEPROP 2 LAST CDS_SEC 1
J 0
(-1550 2600);
PAINT ORANGE (-1550 2600);
DISPLAY INVISIBLE (-1550 2600);
FORCEPROP 2 LAST SEC_TYPE 0603V
J 0
(-1550 2650);
DISPLAY 1.021277 (-1550 2650);
PAINT ORANGE (-1550 2650);
DISPLAY INVISIBLE (-1550 2650);
FORCEPROP 2 LAST SEC 1
J 0
(-1550 2650);
PAINT MONO (-1550 2650);
DISPLAY INVISIBLE (-1550 2650);
FORCEPROP 1 LAST PATH I141
J 0
(-1550 2600);
DISPLAY 0.978723 (-1550 2600);
PAINT WHITE (-1550 2600);
DISPLAY INVISIBLE (-1550 2600);
FORCEADD PVCCIO_CPU1..1
(-7225 4575);
FORCEPROP 3 LASTPIN (-7225 4525) SIG_NAME PVCCIO_CPU1\g
J 0
(-7215 4535);
DISPLAY 0.659574 (-7215 4535);
PAINT MONO (-7215 4535);
DISPLAY INVISIBLE (-7215 4535);
FORCEPROP 2 LAST ROOM PVCCIO_CPU1
J 0
(-7225 4675);
DISPLAY 3.127660 (-7225 4675);
PAINT WHITE (-7225 4675);
DISPLAY INVISIBLE (-7225 4675);
FORCEPROP 1 LAST PATH I144
J 0
(-7175 4600);
DISPLAY 0.872340 (-7175 4600);
PAINT AQUA (-7175 4600);
DISPLAY INVISIBLE (-7175 4600);
FORCEPROP 2 LAST BOM_COST PROC_VRD_PVCCIO_CPU1
J 0
(-7225 4675);
DISPLAY 2.340426 (-7225 4675);
PAINT WHITE (-7225 4675);
DISPLAY INVISIBLE (-7225 4675);
FORCEPROP 2 LAST CDS_LIB mstr_symbols
J 0
(-7225 4575);
PAINT ORANGE (-7225 4575);
DISPLAY INVISIBLE (-7225 4575);
FORCEPROP 1 LAST VOLTAGE 1.1V
J 0
(-7270 4532);
DISPLAY 0.340426 (-7270 4532);
PAINT SKYBLUE (-7270 4532);
DISPLAY INVISIBLE (-7270 4532);
FORCEPROP 1 LAST BODY_TYPE PLUMBING
J 0
(-7270 4532);
DISPLAY 0.340426 (-7270 4532);
PAINT GREEN (-7270 4532);
DISPLAY INVISIBLE (-7270 4532);
FORCEPROP 1 LAST HDL_POWER PVCCIO_CPU1
J 1
(-7225 4625);
DISPLAY 0.872340 (-7225 4625);
PAINT GREEN (-7225 4625);
DISPLAY INVISIBLE (-7225 4625);
FORCEADD OFFPAGE..5
(-4775 2850);
FORCEPROP 2 LAST $XR0 104 
J 0
(-5030 2850);
DISPLAY 0.638298 (-5030 2850);
PAINT MONO (-5030 2850);
FORCEPROP 2 LAST PATH I149
J 0
(-4725 2925);
DISPLAY 1.021277 (-4725 2925);
PAINT ORANGE (-4725 2925);
DISPLAY INVISIBLE (-4725 2925);
FORCEPROP 2 LAST CDS_LIB mstr_standard
J 0
(-4775 2850);
PAINT ORANGE (-4775 2850);
DISPLAY INVISIBLE (-4775 2850);
FORCEPROP 2 LAST ROOM PVSA_CPU0_VSENSE_VR
J 0
(-5175 2925);
PAINT ORANGE (-5175 2925);
DISPLAY INVISIBLE (-5175 2925);
FORCEPROP 2 LAST BOM_COST PROC_VRD_VCCIN_CPU0
J 0
(-4450 2900);
PAINT MONO (-4450 2900);
DISPLAY INVISIBLE (-4450 2900);
FORCEPROP 1 LAST OFFPAGE TRUE
J 0
(-4450 2725);
DISPLAY 0.872340 (-4450 2725);
PAINT GREEN (-4450 2725);
DISPLAY INVISIBLE (-4450 2725);
FORCEPROP 1 LAST COMMENT_BODY TRUE
J 0
(-4675 2775);
DISPLAY 0.872340 (-4675 2775);
PAINT GREEN (-4675 2775);
DISPLAY INVISIBLE (-4675 2775);
FORCEADD OFFPAGE..5
(-4775 2900);
FORCEPROP 2 LAST $XR0 104 
J 0
(-5030 2900);
DISPLAY 0.638298 (-5030 2900);
PAINT MONO (-5030 2900);
FORCEPROP 2 LAST PATH I150
J 0
(-4725 2975);
DISPLAY 1.021277 (-4725 2975);
PAINT ORANGE (-4725 2975);
DISPLAY INVISIBLE (-4725 2975);
FORCEPROP 2 LAST BOM_COST PROC_VRD_VCCIN_CPU0
J 0
(-4450 2950);
PAINT MONO (-4450 2950);
DISPLAY INVISIBLE (-4450 2950);
FORCEPROP 2 LAST ROOM PVSA_CPU0_VSENSE_VR
J 0
(-5175 2975);
PAINT ORANGE (-5175 2975);
DISPLAY INVISIBLE (-5175 2975);
FORCEPROP 2 LAST CDS_LIB mstr_standard
J 0
(-4775 2900);
PAINT ORANGE (-4775 2900);
DISPLAY INVISIBLE (-4775 2900);
FORCEPROP 1 LAST OFFPAGE TRUE
J 0
(-4450 2775);
DISPLAY 0.872340 (-4450 2775);
PAINT GREEN (-4450 2775);
DISPLAY INVISIBLE (-4450 2775);
FORCEPROP 1 LAST COMMENT_BODY TRUE
J 0
(-4675 2825);
DISPLAY 0.872340 (-4675 2825);
PAINT GREEN (-4675 2825);
DISPLAY INVISIBLE (-4675 2825);
FORCEADD OFFPAGE..1
(-4825 4350);
FORCEPROP 2 LAST $XR0 56 
J 0
(-5046 4350);
DISPLAY 0.638298 (-5046 4350);
PAINT MONO (-5046 4350);
FORCEPROP 2 LAST PATH I151
J 0
(-4775 4425);
DISPLAY 1.021277 (-4775 4425);
PAINT ORANGE (-4775 4425);
DISPLAY INVISIBLE (-4775 4425);
FORCEPROP 2 LAST CDS_LIB mstr_standard
J 0
(-4825 4350);
PAINT ORANGE (-4825 4350);
DISPLAY INVISIBLE (-4825 4350);
FORCEPROP 1 LAST OFFPAGE TRUE
J 0
(-4500 4225);
DISPLAY 1.170213 (-4500 4225);
PAINT GREEN (-4500 4225);
DISPLAY INVISIBLE (-4500 4225);
FORCEPROP 1 LAST COMMENT_BODY TRUE
J 0
(-4700 4250);
DISPLAY 1.170213 (-4700 4250);
PAINT GREEN (-4700 4250);
DISPLAY INVISIBLE (-4700 4250);
FORCEADD OFFPAGE..1
(-4775 4000);
FORCEPROP 2 LAST $XR0 56 
J 0
(-5026 4000);
DISPLAY 0.638298 (-5026 4000);
PAINT MONO (-5026 4000);
FORCEPROP 2 LAST PATH I152
J 0
(-4725 4075);
DISPLAY 1.021277 (-4725 4075);
PAINT ORANGE (-4725 4075);
DISPLAY INVISIBLE (-4725 4075);
FORCEPROP 2 LAST CDS_LIB mstr_standard
J 0
(-4775 4000);
PAINT ORANGE (-4775 4000);
DISPLAY INVISIBLE (-4775 4000);
FORCEPROP 1 LAST OFFPAGE TRUE
J 0
(-4450 3875);
DISPLAY 1.170213 (-4450 3875);
PAINT GREEN (-4450 3875);
DISPLAY INVISIBLE (-4450 3875);
FORCEPROP 1 LAST COMMENT_BODY TRUE
J 0
(-4650 3900);
DISPLAY 1.170213 (-4650 3900);
PAINT GREEN (-4650 3900);
DISPLAY INVISIBLE (-4650 3900);
FORCEADD OFFPAGE..4
(-5100 1075);
FORCEPROP 2 LAST $XR2 226 
J 0
(-4674 1075);
DISPLAY 0.638298 (-4674 1075);
PAINT MONO (-4674 1075);
FORCEPROP 2 LAST $XR1 223 
J 0
(-4794 1075);
DISPLAY 0.638298 (-4794 1075);
PAINT MONO (-4794 1075);
FORCEPROP 2 LAST $XR0 55 
J 0
(-4884 1075);
DISPLAY 0.638298 (-4884 1075);
PAINT MONO (-4884 1075);
FORCEPROP 2 LAST PATH I153
J 0
(-4700 1125);
DISPLAY 1.021277 (-4700 1125);
PAINT ORANGE (-4700 1125);
DISPLAY INVISIBLE (-4700 1125);
FORCEPROP 2 LAST ROOM P0V95_FPGA_CPU0_VR
J 0
(-5650 1150);
DISPLAY 1.361702 (-5650 1150);
PAINT ORANGE (-5650 1150);
DISPLAY INVISIBLE (-5650 1150);
FORCEPROP 2 LAST CDS_LIB mstr_standard
J 0
(-5100 1075);
PAINT MONO (-5100 1075);
DISPLAY INVISIBLE (-5100 1075);
FORCEPROP 1 LAST OFFPAGE TRUE
J 0
(-4775 950);
DISPLAY 0.872340 (-4775 950);
PAINT GREEN (-4775 950);
DISPLAY INVISIBLE (-4775 950);
FORCEPROP 1 LAST COMMENT_BODY TRUE
J 0
(-5125 975);
DISPLAY 0.872340 (-5125 975);
PAINT GREEN (-5125 975);
DISPLAY INVISIBLE (-5125 975);
FORCEADD OFFPAGE..3
(-5100 1025);
FORCEPROP 2 LAST $XR2 226 
J 0
(-4676 1025);
DISPLAY 0.638298 (-4676 1025);
PAINT MONO (-4676 1025);
FORCEPROP 2 LAST $XR1 223 
J 0
(-4796 1025);
DISPLAY 0.638298 (-4796 1025);
PAINT MONO (-4796 1025);
FORCEPROP 2 LAST $XR0 55 
J 0
(-4886 1025);
DISPLAY 0.638298 (-4886 1025);
PAINT MONO (-4886 1025);
FORCEPROP 2 LAST PATH I154
J 0
(-4675 1075);
DISPLAY 1.021277 (-4675 1075);
PAINT ORANGE (-4675 1075);
DISPLAY INVISIBLE (-4675 1075);
FORCEPROP 2 LAST ROOM P0V95_FPGA_CPU0_VR
J 0
(-5500 1100);
DISPLAY 1.361702 (-5500 1100);
PAINT ORANGE (-5500 1100);
DISPLAY INVISIBLE (-5500 1100);
FORCEPROP 2 LAST CDS_LIB mstr_standard
J 0
(-5100 1025);
PAINT ORANGE (-5100 1025);
DISPLAY INVISIBLE (-5100 1025);
FORCEPROP 1 LAST OFFPAGE TRUE
J 0
(-4775 900);
DISPLAY 1.170213 (-4775 900);
PAINT GREEN (-4775 900);
DISPLAY INVISIBLE (-4775 900);
FORCEPROP 1 LAST COMMENT_BODY TRUE
J 0
(-5150 925);
DISPLAY 1.170213 (-5150 925);
PAINT GREEN (-5150 925);
DISPLAY INVISIBLE (-5150 925);
FORCEADD OFFPAGE..4
(-5075 1175);
FORCEPROP 2 LAST $XR0 190 
J 0
(-4889 1175);
DISPLAY 0.638298 (-4889 1175);
PAINT MONO (-4889 1175);
FORCEPROP 2 LAST PATH I155
J 0
(-4900 1250);
DISPLAY 1.021277 (-4900 1250);
PAINT ORANGE (-4900 1250);
DISPLAY INVISIBLE (-4900 1250);
FORCEPROP 2 LAST CDS_LIB mstr_standard
J 0
(-5075 1175);
PAINT ORANGE (-5075 1175);
DISPLAY INVISIBLE (-5075 1175);
FORCEPROP 2 LAST ROOM P0V95_FPGA_CPU0_VR
J 0
(-5625 1250);
DISPLAY 1.361702 (-5625 1250);
PAINT ORANGE (-5625 1250);
DISPLAY INVISIBLE (-5625 1250);
FORCEPROP 1 LAST OFFPAGE TRUE
J 0
(-4750 1050);
DISPLAY 0.872340 (-4750 1050);
PAINT GREEN (-4750 1050);
DISPLAY INVISIBLE (-4750 1050);
FORCEPROP 1 LAST COMMENT_BODY TRUE
J 0
(-5100 1075);
DISPLAY 0.872340 (-5100 1075);
PAINT GREEN (-5100 1075);
DISPLAY INVISIBLE (-5100 1075);
FORCEADD OFFPAGE..2
(-5075 1125);
FORCEPROP 2 LAST $XR0 190 
J 0
(-4886 1125);
DISPLAY 0.638298 (-4886 1125);
PAINT MONO (-4886 1125);
FORCEPROP 2 LAST PATH I156
J 0
(-4900 1200);
DISPLAY 1.021277 (-4900 1200);
PAINT ORANGE (-4900 1200);
DISPLAY INVISIBLE (-4900 1200);
FORCEPROP 2 LAST CDS_LIB mstr_standard
J 0
(-5075 1125);
PAINT ORANGE (-5075 1125);
DISPLAY INVISIBLE (-5075 1125);
FORCEPROP 2 LAST ROOM P0V95_FPGA_CPU0_VR
J 0
(-5500 1200);
DISPLAY 1.361702 (-5500 1200);
PAINT ORANGE (-5500 1200);
DISPLAY INVISIBLE (-5500 1200);
FORCEPROP 1 LAST OFFPAGE TRUE
J 0
(-4750 1000);
DISPLAY 1.170213 (-4750 1000);
PAINT GREEN (-4750 1000);
DISPLAY INVISIBLE (-4750 1000);
FORCEPROP 1 LAST COMMENT_BODY TRUE
J 0
(-5120 1030);
DISPLAY 1.170213 (-5120 1030);
PAINT GREEN (-5120 1030);
DISPLAY INVISIBLE (-5120 1030);
FORCEADD OFFPAGE..2
(-5150 1575);
FORCEPROP 2 LAST $XR2 55 
J 0
(-4721 1575);
DISPLAY 0.638298 (-4721 1575);
PAINT MONO (-4721 1575);
FORCEPROP 2 LAST $XR1 226 
J 0
(-4841 1575);
DISPLAY 0.638298 (-4841 1575);
PAINT MONO (-4841 1575);
FORCEPROP 2 LAST $XR0 223 
J 0
(-4961 1575);
DISPLAY 0.638298 (-4961 1575);
PAINT MONO (-4961 1575);
FORCEPROP 2 LAST PATH I157
J 0
(-4700 1625);
DISPLAY 1.021277 (-4700 1625);
PAINT ORANGE (-4700 1625);
DISPLAY INVISIBLE (-4700 1625);
FORCEPROP 2 LAST ROOM P0V95_FPGA_CPU0_VR
J 0
(-5575 1650);
DISPLAY 1.361702 (-5575 1650);
PAINT ORANGE (-5575 1650);
DISPLAY INVISIBLE (-5575 1650);
FORCEPROP 2 LAST CDS_LIB mstr_standard
J 0
(-5150 1575);
PAINT ORANGE (-5150 1575);
DISPLAY INVISIBLE (-5150 1575);
FORCEPROP 1 LAST OFFPAGE TRUE
J 0
(-4825 1450);
DISPLAY 1.170213 (-4825 1450);
PAINT GREEN (-4825 1450);
DISPLAY INVISIBLE (-4825 1450);
FORCEPROP 1 LAST COMMENT_BODY TRUE
J 0
(-5195 1480);
DISPLAY 1.170213 (-5195 1480);
PAINT GREEN (-5195 1480);
DISPLAY INVISIBLE (-5195 1480);
FORCEADD VCC_CORE..1
(-2300 4600);
FORCEPROP 3 LASTPIN (-2300 4550) SIG_NAME PVCCMCP_CPU1\g
J 0
(-2290 4560);
DISPLAY 0.659574 (-2290 4560);
PAINT MONO (-2290 4560);
DISPLAY INVISIBLE (-2290 4560);
FORCEPROP 1 LAST HDL_POWER PVCCMCP_CPU1
J 1
(-2300 4650);
DISPLAY 0.617021 (-2300 4650);
PAINT GREEN (-2300 4650);
FORCEPROP 1 LAST PATH I161
J 0
(-2250 4625);
DISPLAY 0.872340 (-2250 4625);
PAINT AQUA (-2250 4625);
DISPLAY INVISIBLE (-2250 4625);
FORCEPROP 2 LAST CDS_LIB mstr_symbols
J 0
(-2300 4600);
PAINT ORANGE (-2300 4600);
DISPLAY INVISIBLE (-2300 4600);
FORCEPROP 0 LAST VOLTAGE +0.95
J 0
(-2300 4750);
DISPLAY 1.021277 (-2300 4750);
PAINT SKYBLUE (-2300 4750);
DISPLAY INVISIBLE (-2300 4750);
FORCEADD VCC_CORE..1
(-5150 3700);
FORCEPROP 3 LASTPIN (-5150 3650) SIG_NAME PVCCMCP_CPU1\g
J 0
(-5140 3660);
DISPLAY 0.659574 (-5140 3660);
PAINT MONO (-5140 3660);
DISPLAY INVISIBLE (-5140 3660);
FORCEPROP 1 LAST HDL_POWER PVCCMCP_CPU1
J 1
(-5150 3750);
DISPLAY 0.617021 (-5150 3750);
PAINT GREEN (-5150 3750);
FORCEPROP 2 LAST CDS_LIB mstr_symbols
J 0
(-5150 3700);
PAINT ORANGE (-5150 3700);
DISPLAY INVISIBLE (-5150 3700);
FORCEPROP 1 LAST PATH I162
J 0
(-5100 3725);
DISPLAY 0.872340 (-5100 3725);
PAINT AQUA (-5100 3725);
DISPLAY INVISIBLE (-5100 3725);
FORCEADD VCC_CORE..1
(-1900 2675);
FORCEPROP 3 LASTPIN (-1900 2625) SIG_NAME P1V8_MCP_CPU1\g
J 0
(-1890 2635);
DISPLAY 0.659574 (-1890 2635);
PAINT MONO (-1890 2635);
DISPLAY INVISIBLE (-1890 2635);
FORCEPROP 1 LAST HDL_POWER P1V8_MCP_CPU1
J 1
(-1900 2725);
DISPLAY 0.617021 (-1900 2725);
PAINT GREEN (-1900 2725);
FORCEPROP 1 LAST PATH I164
J 0
(-1850 2700);
DISPLAY 0.872340 (-1850 2700);
PAINT AQUA (-1850 2700);
DISPLAY INVISIBLE (-1850 2700);
FORCEPROP 2 LAST CDS_LIB mstr_symbols
J 0
(-1900 2675);
PAINT ORANGE (-1900 2675);
DISPLAY INVISIBLE (-1900 2675);
FORCEPROP 0 LAST VOLTAGE 1.8
J 0
(-1900 2825);
DISPLAY 1.021277 (-1900 2825);
PAINT SKYBLUE (-1900 2825);
DISPLAY INVISIBLE (-1900 2825);
FORCEADD VCC_CORE..1
(-1300 2675);
FORCEPROP 3 LASTPIN (-1300 2625) SIG_NAME P1V8_MCP_CPU1\g
J 0
(-1290 2635);
DISPLAY 0.659574 (-1290 2635);
PAINT MONO (-1290 2635);
DISPLAY INVISIBLE (-1290 2635);
FORCEPROP 1 LAST HDL_POWER P1V8_MCP_CPU1
J 1
(-1300 2725);
DISPLAY 0.617021 (-1300 2725);
PAINT GREEN (-1300 2725);
FORCEPROP 1 LAST PATH I165
J 0
(-1250 2700);
DISPLAY 0.872340 (-1250 2700);
PAINT AQUA (-1250 2700);
DISPLAY INVISIBLE (-1250 2700);
FORCEPROP 2 LAST CDS_LIB mstr_symbols
J 0
(-1300 2675);
PAINT ORANGE (-1300 2675);
DISPLAY INVISIBLE (-1300 2675);
FORCEPROP 0 LAST VOLTAGE 1.8
J 0
(-1300 2825);
DISPLAY 1.021277 (-1300 2825);
PAINT SKYBLUE (-1300 2825);
DISPLAY INVISIBLE (-1300 2825);
FORCEADD VCC_CORE..1
(-1600 4175);
FORCEPROP 3 LASTPIN (-1600 4125) SIG_NAME PVCCIOMCP_CPU1\g
J 0
(-1590 4135);
DISPLAY 0.659574 (-1590 4135);
PAINT MONO (-1590 4135);
DISPLAY INVISIBLE (-1590 4135);
FORCEPROP 1 LAST HDL_POWER PVCCIOMCP_CPU1
J 1
(-1600 4225);
DISPLAY 0.617021 (-1600 4225);
PAINT GREEN (-1600 4225);
FORCEPROP 0 LAST VOLTAGE +0.95
J 0
(-1600 4325);
DISPLAY 1.021277 (-1600 4325);
PAINT SKYBLUE (-1600 4325);
DISPLAY INVISIBLE (-1600 4325);
FORCEPROP 2 LAST CDS_LIB mstr_symbols
J 0
(-1600 4175);
PAINT ORANGE (-1600 4175);
DISPLAY INVISIBLE (-1600 4175);
FORCEPROP 1 LAST PATH I166
J 0
(-1550 4200);
DISPLAY 0.872340 (-1550 4200);
PAINT AQUA (-1550 4200);
DISPLAY INVISIBLE (-1550 4200);
FORCEADD VCC_CORE..1
(-1900 4125);
FORCEPROP 3 LASTPIN (-1900 4075) SIG_NAME PVCCIOMCP_CPU1\g
J 0
(-1890 4085);
DISPLAY 0.659574 (-1890 4085);
PAINT MONO (-1890 4085);
DISPLAY INVISIBLE (-1890 4085);
FORCEPROP 1 LAST HDL_POWER PVCCIOMCP_CPU1
J 1
(-1900 4175);
DISPLAY 0.617021 (-1900 4175);
PAINT GREEN (-1900 4175);
FORCEPROP 0 LAST VOLTAGE +0.95
J 0
(-1900 4275);
DISPLAY 1.021277 (-1900 4275);
PAINT SKYBLUE (-1900 4275);
DISPLAY INVISIBLE (-1900 4275);
FORCEPROP 2 LAST CDS_LIB mstr_symbols
J 0
(-1900 4125);
PAINT ORANGE (-1900 4125);
DISPLAY INVISIBLE (-1900 4125);
FORCEPROP 1 LAST PATH I167
J 0
(-1850 4150);
DISPLAY 0.872340 (-1850 4150);
PAINT AQUA (-1850 4150);
DISPLAY INVISIBLE (-1850 4150);
FORCEADD VCC_CORE..1
(-1900 3325);
FORCEPROP 3 LASTPIN (-1900 3275) SIG_NAME PVCCMCP_CPU1\g
J 0
(-1890 3285);
DISPLAY 0.659574 (-1890 3285);
PAINT MONO (-1890 3285);
DISPLAY INVISIBLE (-1890 3285);
FORCEPROP 1 LAST HDL_POWER PVCCMCP_CPU1
J 1
(-1900 3375);
DISPLAY 0.617021 (-1900 3375);
PAINT GREEN (-1900 3375);
FORCEPROP 0 LAST VOLTAGE +0.95
J 0
(-1900 3475);
DISPLAY 1.021277 (-1900 3475);
PAINT SKYBLUE (-1900 3475);
DISPLAY INVISIBLE (-1900 3475);
FORCEPROP 2 LAST CDS_LIB mstr_symbols
J 0
(-1900 3325);
PAINT ORANGE (-1900 3325);
DISPLAY INVISIBLE (-1900 3325);
FORCEPROP 1 LAST PATH I168
J 0
(-1850 3350);
DISPLAY 0.872340 (-1850 3350);
PAINT AQUA (-1850 3350);
DISPLAY INVISIBLE (-1850 3350);
FORCEADD RES..2
(-7950 775);
FORCEPROP 1 LAST PACK_TYPE 0402
J 0
(-7910 600);
DISPLAY 0.617021 (-7910 600);
PAINT SKYBLUE (-7910 600);
FORCEPROP 1 LAST PART_NUMBER G21796-078
J 0
(-7910 650);
DISPLAY 0.617021 (-7910 650);
PAINT BLUE (-7910 650);
FORCEPROP 1 LAST WATTAGE 1/16W
J 0
(-7910 750);
DISPLAY 0.617021 (-7910 750);
PAINT SKYBLUE (-7910 750);
FORCEPROP 0 LAST GROUP MCP
J 0
(-7906 551);
DISPLAY 0.638298 (-7906 551);
PAINT BROWN (-7906 551);
DISPLAY BOTH (-7906 551);
FORCEPROP 1 LASTPIN (-7950 875) $PN 1
J 0
(-7945 837);
DISPLAY 0.617021 (-7945 837);
PAINT ORANGE (-7945 837);
FORCEPROP 1 LASTPIN (-7950 675) $PN 2
J 0
(-7945 685);
DISPLAY 0.617021 (-7945 685);
PAINT ORANGE (-7945 685);
FORCEPROP 1 LAST MATERIAL CHIP
J 0
(-7910 700);
DISPLAY 0.617021 (-7910 700);
PAINT SKYBLUE (-7910 700);
FORCEPROP 1 LAST TOLERANCE 1%
J 0
(-7905 800);
DISPLAY 0.617021 (-7905 800);
PAINT SKYBLUE (-7905 800);
FORCEPROP 1 LAST VALUE 8.06K
J 0
(-7905 850);
DISPLAY 0.617021 (-7905 850);
PAINT SKYBLUE (-7905 850);
FORCEPROP 1 LAST LOCATION R4C12
J 0
(-7905 900);
DISPLAY 0.617021 (-7905 900);
PAINT AQUA (-7905 900);
FORCEPROP 0 LAST ROOM PVCCIN_CPU0_VR
J 0
(-7900 1000);
DISPLAY 1.021277 (-7900 1000);
PAINT ORANGE (-7900 1000);
DISPLAY INVISIBLE (-7900 1000);
FORCEPROP 1 LAST PATH I169
J 0
(-7900 950);
DISPLAY 0.978723 (-7900 950);
PAINT WHITE (-7900 950);
DISPLAY INVISIBLE (-7900 950);
FORCEPROP 2 LAST SEC 1
J 0
(-7900 1000);
PAINT MONO (-7900 1000);
DISPLAY INVISIBLE (-7900 1000);
FORCEPROP 2 LAST CDS_LIB mstr_discrete
J 0
(-7950 775);
PAINT ORANGE (-7950 775);
DISPLAY INVISIBLE (-7950 775);
FORCEPROP 2 LAST SEC_TYPE 0402
J 0
(-7900 1000);
DISPLAY 1.021277 (-7900 1000);
PAINT ORANGE (-7900 1000);
DISPLAY INVISIBLE (-7900 1000);
FORCEADD RES..2
(-7600 750);
FORCEPROP 1 LAST PART_NUMBER G21796-043
J 0
(-7560 625);
DISPLAY 0.617021 (-7560 625);
PAINT BLUE (-7560 625);
FORCEPROP 0 LAST GROUP MCP
J 0
(-7562 527);
DISPLAY 0.638298 (-7562 527);
PAINT BROWN (-7562 527);
DISPLAY BOTH (-7562 527);
FORCEPROP 1 LAST LOCATION R4C11
J 0
(-7555 875);
DISPLAY 0.617021 (-7555 875);
PAINT AQUA (-7555 875);
FORCEPROP 1 LAST VALUE 3.16K
J 0
(-7555 825);
DISPLAY 0.617021 (-7555 825);
PAINT SKYBLUE (-7555 825);
FORCEPROP 1 LAST TOLERANCE 1%
J 0
(-7555 775);
DISPLAY 0.617021 (-7555 775);
PAINT SKYBLUE (-7555 775);
FORCEPROP 1 LAST PACK_TYPE 0402
J 0
(-7560 575);
DISPLAY 0.617021 (-7560 575);
PAINT SKYBLUE (-7560 575);
FORCEPROP 1 LAST MATERIAL CHIP
J 0
(-7560 675);
DISPLAY 0.617021 (-7560 675);
PAINT SKYBLUE (-7560 675);
FORCEPROP 1 LAST WATTAGE 1/16W
J 0
(-7560 725);
DISPLAY 0.617021 (-7560 725);
PAINT SKYBLUE (-7560 725);
FORCEPROP 1 LASTPIN (-7600 650) $PN 2
J 0
(-7595 660);
DISPLAY 0.617021 (-7595 660);
PAINT ORANGE (-7595 660);
FORCEPROP 1 LASTPIN (-7600 850) $PN 1
J 0
(-7595 812);
DISPLAY 0.617021 (-7595 812);
PAINT ORANGE (-7595 812);
FORCEPROP 1 LAST PATH I170
J 0
(-7550 925);
DISPLAY 0.978723 (-7550 925);
PAINT WHITE (-7550 925);
DISPLAY INVISIBLE (-7550 925);
FORCEPROP 2 LAST SEC_TYPE 0402
J 0
(-7550 975);
DISPLAY 1.021277 (-7550 975);
PAINT ORANGE (-7550 975);
DISPLAY INVISIBLE (-7550 975);
FORCEPROP 2 LAST CDS_LIB mstr_discrete
J 0
(-7600 750);
PAINT ORANGE (-7600 750);
DISPLAY INVISIBLE (-7600 750);
FORCEPROP 2 LAST SEC 1
J 0
(-7550 975);
PAINT MONO (-7550 975);
DISPLAY INVISIBLE (-7550 975);
FORCEPROP 0 LAST ROOM PVCCIN_CPU0_VR
J 0
(-7550 975);
DISPLAY 1.021277 (-7550 975);
PAINT ORANGE (-7550 975);
DISPLAY INVISIBLE (-7550 975);
FORCEADD GND..1
(-7950 450);
FORCEPROP 3 LASTPIN (-7950 500) SIG_NAME GND\g
J 0
(-7940 510);
DISPLAY 0.659574 (-7940 510);
PAINT MONO (-7940 510);
DISPLAY INVISIBLE (-7940 510);
FORCEPROP 1 LAST SIZE 1B
J 0
(-7875 400);
DISPLAY 1.127660 (-7875 400);
PAINT AQUA (-7875 400);
DISPLAY INVISIBLE (-7875 400);
FORCEPROP 1 LAST PATH I171
J 0
(-7875 450);
DISPLAY 0.872340 (-7875 450);
PAINT AQUA (-7875 450);
DISPLAY INVISIBLE (-7875 450);
FORCEPROP 2 LAST CDS_LIB mstr_symbols
J 0
(-7950 450);
PAINT ORANGE (-7950 450);
DISPLAY INVISIBLE (-7950 450);
FORCEPROP 1 LAST VOLTAGE 0.0V
J 0
(-7995 407);
DISPLAY 0.340426 (-7995 407);
PAINT SKYBLUE (-7995 407);
DISPLAY INVISIBLE (-7995 407);
FORCEPROP 1 LAST BODY_TYPE PLUMBING
J 0
(-7995 407);
DISPLAY 0.340426 (-7995 407);
PAINT GREEN (-7995 407);
DISPLAY INVISIBLE (-7995 407);
FORCEPROP 1 LAST HDL_POWER GND
J 0
(-7950 600);
PAINT GREEN (-7950 600);
DISPLAY INVISIBLE (-7950 600);
FORCEADD P3V3..1
(-7325 4500);
FORCEPROP 3 LASTPIN (-7325 4450) SIG_NAME P3V3\g
J 0
(-7315 4460);
DISPLAY 0.659574 (-7315 4460);
PAINT MONO (-7315 4460);
DISPLAY INVISIBLE (-7315 4460);
FORCEPROP 1 LAST PATH I173
J 0
(-7280 4502);
DISPLAY 0.340426 (-7280 4502);
PAINT GREEN (-7280 4502);
DISPLAY INVISIBLE (-7280 4502);
FORCEPROP 2 LAST CDS_LIB mstr_symbols
J 0
(-7325 4500);
PAINT ORANGE (-7325 4500);
DISPLAY INVISIBLE (-7325 4500);
FORCEPROP 1 LAST SIZE 1B
J 0
(-7280 4522);
DISPLAY 0.340426 (-7280 4522);
PAINT GREEN (-7280 4522);
DISPLAY INVISIBLE (-7280 4522);
FORCEPROP 1 LAST VOLTAGE +3.3V
J 0
(-7225 4650);
DISPLAY 1.021277 (-7225 4650);
PAINT SKYBLUE (-7225 4650);
DISPLAY INVISIBLE (-7225 4650);
FORCEPROP 1 LAST BODY_TYPE PLUMBING
J 0
(-7370 4457);
DISPLAY 0.340426 (-7370 4457);
PAINT GREEN (-7370 4457);
DISPLAY INVISIBLE (-7370 4457);
FORCEPROP 1 LAST HDL_POWER P3V3
J 0
(-7650 4375);
DISPLAY 0.872340 (-7650 4375);
PAINT ORANGE (-7650 4375);
DISPLAY INVISIBLE (-7650 4375);
FORCEADD OFFPAGE..1
(-7975 4225);
FORCEPROP 2 LAST $XR0 104 
J 0
(-8227 4225);
DISPLAY 0.638298 (-8227 4225);
PAINT MONO (-8227 4225);
FORCEPROP 2 LAST PATH I174
J 0
(-7925 4300);
DISPLAY 1.021277 (-7925 4300);
PAINT ORANGE (-7925 4300);
DISPLAY INVISIBLE (-7925 4300);
FORCEPROP 2 LAST CDS_LIB mstr_standard
J 0
(-7975 4225);
PAINT ORANGE (-7975 4225);
DISPLAY INVISIBLE (-7975 4225);
FORCEPROP 1 LAST OFFPAGE TRUE
J 0
(-7650 4100);
DISPLAY 0.872340 (-7650 4100);
PAINT GREEN (-7650 4100);
DISPLAY INVISIBLE (-7650 4100);
FORCEPROP 1 LAST COMMENT_BODY TRUE
J 0
(-7850 4125);
DISPLAY 0.872340 (-7850 4125);
PAINT GREEN (-7850 4125);
DISPLAY INVISIBLE (-7850 4125);
FORCEADD CAPP..1
(-1300 3100);
FORCEPROP 1 LASTPIN (-1300 3000) $PN 2
J 0
(-1290 2985);
DISPLAY 0.787234 (-1290 2985);
PAINT ORANGE (-1290 2985);
FORCEPROP 1 LAST PACK_TYPE 3018
J 0
(-1250 2950);
DISPLAY 0.617021 (-1250 2950);
PAINT SKYBLUE (-1250 2950);
FORCEPROP 1 LAST VOLTAGE 2.5V
J 0
(-1250 3050);
DISPLAY 0.659574 (-1250 3050);
PAINT SKYBLUE (-1250 3050);
FORCEPROP 1 LAST TOLERANCE 20%
J 0
(-1250 3100);
DISPLAY 0.617021 (-1250 3100);
PAINT SKYBLUE (-1250 3100);
FORCEPROP 1 LAST VALUE 470UF
J 0
(-1250 3150);
DISPLAY 0.617021 (-1250 3150);
PAINT SKYBLUE (-1250 3150);
FORCEPROP 1 LAST LOCATION C4E29
J 0
(-1250 3200);
DISPLAY 0.617021 (-1250 3200);
PAINT AQUA (-1250 3200);
FORCEPROP 1 LASTPIN (-1300 3200) $PN 1
J 0
(-1290 3185);
DISPLAY 0.787234 (-1290 3185);
PAINT ORANGE (-1290 3185);
FORCEPROP 1 LAST MATERIAL ALUM
J 0
(-1250 3000);
DISPLAY 0.617021 (-1250 3000);
PAINT SKYBLUE (-1250 3000);
FORCEPROP 0 LAST GROUP PWR_MCP_CAP
J 0
(-1260 2851);
DISPLAY 0.638298 (-1260 2851);
PAINT BROWN (-1260 2851);
DISPLAY BOTH (-1260 2851);
FORCEPROP 1 LAST PART_NUMBER 699013-049
J 0
(-1250 2900);
DISPLAY 0.617021 (-1250 2900);
PAINT BLUE (-1250 2900);
FORCEPROP 2 LAST CDS_LIB mstr_discrete
J 0
(-1300 3100);
DISPLAY INVISIBLE (-1300 3100);
FORCEPROP 1 LAST PATH I175
J 0
(-1250 3250);
DISPLAY 0.978723 (-1250 3250);
PAINT ORANGE (-1250 3250);
DISPLAY INVISIBLE (-1250 3250);
FORCEPROP 2 LAST BOM_COST PVMCP_MCP_CPU1_VR
J 0
(-1250 3250);
DISPLAY 1.617021 (-1250 3250);
PAINT WHITE (-1250 3250);
DISPLAY INVISIBLE (-1250 3250);
FORCEPROP 2 LAST ROOM PVMCP_MCP_CPU1_VR
J 0
(-1250 3225);
DISPLAY 1.617021 (-1250 3225);
PAINT WHITE (-1250 3225);
DISPLAY INVISIBLE (-1250 3225);
FORCEPROP 2 LAST SEC_TYPE 3018
J 0
(-1250 3300);
DISPLAY 1.021277 (-1250 3300);
PAINT ORANGE (-1250 3300);
DISPLAY INVISIBLE (-1250 3300);
FORCEPROP 0 LAST SEC 1
J 0
(-1250 3250);
DISPLAY 0.680851 (-1250 3250);
PAINT MONO (-1250 3250);
DISPLAY INVISIBLE (-1250 3250);
FORCEADD OFFPAGE..3
(-5100 1225);
FORCEPROP 2 LAST $XR2 213 
J 0
(-4676 1225);
DISPLAY 0.638298 (-4676 1225);
PAINT MONO (-4676 1225);
FORCEPROP 2 LAST $XR1 206 
J 0
(-4796 1225);
DISPLAY 0.638298 (-4796 1225);
PAINT MONO (-4796 1225);
FORCEPROP 2 LAST $XR0 55 
J 0
(-4886 1225);
DISPLAY 0.638298 (-4886 1225);
PAINT MONO (-4886 1225);
FORCEPROP 2 LAST PATH I2
J 0
(-4900 1300);
DISPLAY 1.021277 (-4900 1300);
PAINT ORANGE (-4900 1300);
DISPLAY INVISIBLE (-4900 1300);
FORCEPROP 2 LAST ROOM P0V95_FPGA_CPU0_VR
J 0
(-5500 1300);
DISPLAY 1.361702 (-5500 1300);
PAINT ORANGE (-5500 1300);
DISPLAY INVISIBLE (-5500 1300);
FORCEPROP 2 LAST CDS_LIB mstr_standard
J 0
(-5100 1225);
PAINT ORANGE (-5100 1225);
DISPLAY INVISIBLE (-5100 1225);
FORCEPROP 1 LAST OFFPAGE TRUE
J 0
(-4775 1100);
DISPLAY 1.170213 (-4775 1100);
PAINT GREEN (-4775 1100);
DISPLAY INVISIBLE (-4775 1100);
FORCEPROP 1 LAST COMMENT_BODY TRUE
J 0
(-5150 1125);
DISPLAY 1.170213 (-5150 1125);
PAINT GREEN (-5150 1125);
DISPLAY INVISIBLE (-5150 1125);
FORCEADD CAPP..1
(-1900 3950);
FORCEPROP 1 LASTPIN (-1900 3850) $PN 2
J 0
(-1890 3835);
DISPLAY 0.617021 (-1890 3835);
PAINT ORANGE (-1890 3835);
FORCEPROP 1 LASTPIN (-1900 4050) $PN 1
J 0
(-1890 4035);
DISPLAY 0.617021 (-1890 4035);
PAINT ORANGE (-1890 4035);
FORCEPROP 1 LAST TOLERANCE 20%
J 0
(-1850 3950);
DISPLAY 0.617021 (-1850 3950);
PAINT SKYBLUE (-1850 3950);
FORCEPROP 1 LAST VOLTAGE 2.5V
J 0
(-1850 3900);
DISPLAY 0.617021 (-1850 3900);
PAINT SKYBLUE (-1850 3900);
FORCEPROP 1 LAST MATERIAL ALUM
J 0
(-1850 3850);
DISPLAY 0.617021 (-1850 3850);
PAINT SKYBLUE (-1850 3850);
FORCEPROP 1 LAST PACK_TYPE 3018
J 0
(-1850 3800);
DISPLAY 0.617021 (-1850 3800);
PAINT SKYBLUE (-1850 3800);
FORCEPROP 1 LAST PART_NUMBER 699013-049
J 0
(-1850 3750);
DISPLAY 0.617021 (-1850 3750);
PAINT BLUE (-1850 3750);
FORCEPROP 1 LAST LOCATION C4C1
J 0
(-1850 4050);
DISPLAY 0.617021 (-1850 4050);
PAINT AQUA (-1850 4050);
FORCEPROP 1 LAST VALUE 470UF
J 0
(-1850 4000);
DISPLAY 0.617021 (-1850 4000);
PAINT SKYBLUE (-1850 4000);
FORCEPROP 0 LAST GROUP PWR_MCP_CAP
J 0
(-1860 3626);
DISPLAY 0.638298 (-1860 3626);
PAINT BROWN (-1860 3626);
DISPLAY BOTH (-1860 3626);
FORCEPROP 2 LAST CDS_LIB mstr_discrete
J 0
(-1900 3950);
PAINT ORANGE (-1900 3950);
DISPLAY INVISIBLE (-1900 3950);
FORCEPROP 2 LAST SEC_TYPE 3018
J 0
(-1850 4150);
DISPLAY 1.021277 (-1850 4150);
PAINT ORANGE (-1850 4150);
DISPLAY INVISIBLE (-1850 4150);
FORCEPROP 2 LAST BOM_COST PROC_VRD_VCCIN_CPU1
J 0
(-1850 4100);
PAINT MONO (-1850 4100);
DISPLAY INVISIBLE (-1850 4100);
FORCEPROP 2 LAST SEC 1
J 0
(-1850 4150);
PAINT MONO (-1850 4150);
DISPLAY INVISIBLE (-1850 4150);
FORCEPROP 2 LAST CDS_LOCATION C4C1
J 0
(-1850 4050);
DISPLAY 0.617021 (-1850 4050);
PAINT AQUA (-1850 4050);
DISPLAY INVISIBLE (-1850 4050);
FORCEPROP 1 LAST PATH I29
J 0
(-1850 4100);
DISPLAY 0.978723 (-1850 4100);
PAINT ORANGE (-1850 4100);
DISPLAY INVISIBLE (-1850 4100);
FORCEPROP 2 LAST ROOM P0V95_MCP_CPU1_DECAP_VR
J 0
(-1850 4075);
PAINT MONO (-1850 4075);
DISPLAY INVISIBLE (-1850 4075);
FORCEADD GND..1
(-1900 3775);
FORCEPROP 3 LASTPIN (-1900 3825) SIG_NAME GND\g
J 0
(-1890 3835);
DISPLAY 0.659574 (-1890 3835);
PAINT MONO (-1890 3835);
DISPLAY INVISIBLE (-1890 3835);
FORCEPROP 1 LAST HDL_POWER GND
J 0
(-1900 3925);
DISPLAY 1.723404 (-1900 3925);
PAINT GREEN (-1900 3925);
DISPLAY INVISIBLE (-1900 3925);
FORCEPROP 1 LAST BODY_TYPE PLUMBING
J 0
(-1945 3732);
DISPLAY 0.340426 (-1945 3732);
PAINT GREEN (-1945 3732);
DISPLAY INVISIBLE (-1945 3732);
FORCEPROP 1 LAST VOLTAGE 0
J 0
(-1900 3775);
PAINT SKYBLUE (-1900 3775);
DISPLAY INVISIBLE (-1900 3775);
FORCEPROP 1 LAST SIZE 1B
J 0
(-1825 3725);
DISPLAY 1.723404 (-1825 3725);
PAINT GREEN (-1825 3725);
DISPLAY INVISIBLE (-1825 3725);
FORCEPROP 2 LAST CDS_LIB mstr_symbols
J 0
(-1900 3775);
PAINT ORANGE (-1900 3775);
DISPLAY INVISIBLE (-1900 3775);
FORCEPROP 2 LAST BOM_COST PROC_VRD_VCCIN_CPU0
J 0
(-2275 3850);
DISPLAY 1.446809 (-2275 3850);
PAINT MONO (-2275 3850);
DISPLAY INVISIBLE (-2275 3850);
FORCEPROP 1 LAST PATH I30
J 0
(-1825 3775);
DISPLAY 0.872340 (-1825 3775);
PAINT AQUA (-1825 3775);
DISPLAY INVISIBLE (-1825 3775);
FORCEPROP 2 LAST ROOM PVSA_CPU0_DECAP_VR
J 0
(-2450 3850);
DISPLAY 1.936170 (-2450 3850);
PAINT ORANGE (-2450 3850);
DISPLAY INVISIBLE (-2450 3850);
FORCEADD CAP_A..1
(-1300 3950);
FORCEPROP 1 LASTPIN (-1300 4050) $PN 1
J 0
(-1290 4030);
DISPLAY 0.617021 (-1290 4030);
PAINT ORANGE (-1290 4030);
FORCEPROP 1 LASTPIN (-1300 3850) $PN 2
J 0
(-1290 3830);
DISPLAY 0.617021 (-1290 3830);
PAINT ORANGE (-1290 3830);
FORCEPROP 1 LAST LOCATION C3C2
J 0
(-1250 4050);
DISPLAY 0.617021 (-1250 4050);
PAINT AQUA (-1250 4050);
FORCEPROP 1 LAST VOLTAGE 6.3V
J 0
(-1250 3950);
DISPLAY 0.617021 (-1250 3950);
PAINT SKYBLUE (-1250 3950);
FORCEPROP 1 LAST TOLERANCE 10%
J 0
(-1250 3900);
DISPLAY 0.617021 (-1250 3900);
PAINT SKYBLUE (-1250 3900);
FORCEPROP 1 LAST MATERIAL X6S
J 0
(-1250 3850);
DISPLAY 0.617021 (-1250 3850);
PAINT SKYBLUE (-1250 3850);
FORCEPROP 1 LAST PACK_TYPE 0402V
J 0
(-1250 3750);
DISPLAY 0.617021 (-1250 3750);
PAINT SKYBLUE (-1250 3750);
FORCEPROP 1 LAST PART_NUMBER D97712-004
J 0
(-1250 3800);
DISPLAY 0.617021 (-1250 3800);
PAINT BLUE (-1250 3800);
FORCEPROP 1 LAST VALUE 1.0UF
J 0
(-1250 4000);
DISPLAY 0.617021 (-1250 4000);
PAINT SKYBLUE (-1250 4000);
FORCEPROP 0 LAST GROUP PWR_MCP_CAP
J 0
(-1260 3651);
DISPLAY 0.638298 (-1260 3651);
PAINT BROWN (-1260 3651);
DISPLAY BOTH (-1260 3651);
FORCEPROP 2 LAST CDS_LOCATION C3C2
J 0
(-1250 4050);
DISPLAY 0.617021 (-1250 4050);
PAINT AQUA (-1250 4050);
DISPLAY INVISIBLE (-1250 4050);
FORCEPROP 2 LAST CDS_LIB dev_discrete
J 2
(-1300 3950);
PAINT ORANGE (-1300 3950);
DISPLAY INVISIBLE (-1300 3950);
FORCEPROP 2 LAST CDS_SEC 1
J 2
(-1250 4100);
PAINT ORANGE (-1250 4100);
DISPLAY INVISIBLE (-1250 4100);
FORCEPROP 2 LAST SEC_TYPE 0402V
J 2
(-1250 4150);
DISPLAY 1.021277 (-1250 4150);
PAINT ORANGE (-1250 4150);
DISPLAY INVISIBLE (-1250 4150);
FORCEPROP 2 LAST SEC 1
J 2
(-1250 4150);
DISPLAY 0.680851 (-1250 4150);
PAINT MONO (-1250 4150);
DISPLAY INVISIBLE (-1250 4150);
FORCEPROP 1 LAST PATH I31
J 0
(-1250 4100);
DISPLAY 0.978723 (-1250 4100);
PAINT WHITE (-1250 4100);
DISPLAY INVISIBLE (-1250 4100);
FORCEPROP 2 LAST ROOM P0V95_FPGA_CPU1
J 0
(-1250 4100);
DISPLAY 1.659574 (-1250 4100);
PAINT WHITE (-1250 4100);
DISPLAY INVISIBLE (-1250 4100);
FORCEADD GND..1
(-1600 3675);
FORCEPROP 3 LASTPIN (-1600 3725) SIG_NAME GND\g
J 0
(-1590 3735);
DISPLAY 0.659574 (-1590 3735);
PAINT MONO (-1590 3735);
DISPLAY INVISIBLE (-1590 3735);
FORCEPROP 1 LAST HDL_POWER GND
J 0
(-1600 3825);
PAINT GREEN (-1600 3825);
DISPLAY INVISIBLE (-1600 3825);
FORCEPROP 1 LAST BODY_TYPE PLUMBING
J 0
(-1645 3632);
DISPLAY 0.340426 (-1645 3632);
PAINT GREEN (-1645 3632);
DISPLAY INVISIBLE (-1645 3632);
FORCEPROP 1 LAST VOLTAGE 0.0V
J 0
(-1645 3632);
DISPLAY 0.340426 (-1645 3632);
PAINT SKYBLUE (-1645 3632);
DISPLAY INVISIBLE (-1645 3632);
FORCEPROP 2 LAST CDS_LIB mstr_symbols
J 0
(-1600 3675);
PAINT ORANGE (-1600 3675);
DISPLAY INVISIBLE (-1600 3675);
FORCEPROP 1 LAST SIZE 1B
J 0
(-1525 3625);
DISPLAY 1.404255 (-1525 3625);
PAINT AQUA (-1525 3625);
DISPLAY INVISIBLE (-1525 3625);
FORCEPROP 1 LAST PATH I37
J 0
(-1525 3675);
DISPLAY 0.872340 (-1525 3675);
PAINT AQUA (-1525 3675);
DISPLAY INVISIBLE (-1525 3675);
FORCEADD CAP_A..1
(-1600 3950);
FORCEPROP 1 LAST VOLTAGE 6.3V
J 0
(-1550 3950);
DISPLAY 0.617021 (-1550 3950);
PAINT SKYBLUE (-1550 3950);
FORCEPROP 1 LAST MATERIAL X6S
J 0
(-1550 3850);
DISPLAY 0.617021 (-1550 3850);
PAINT SKYBLUE (-1550 3850);
FORCEPROP 1 LAST PACK_TYPE 0402V
J 0
(-1550 3750);
DISPLAY 0.617021 (-1550 3750);
PAINT SKYBLUE (-1550 3750);
FORCEPROP 1 LASTPIN (-1600 3850) $PN 2
J 0
(-1590 3830);
DISPLAY 0.617021 (-1590 3830);
PAINT ORANGE (-1590 3830);
FORCEPROP 1 LAST LOCATION C3C1
J 0
(-1550 4050);
DISPLAY 0.617021 (-1550 4050);
PAINT AQUA (-1550 4050);
FORCEPROP 1 LAST TOLERANCE 10%
J 0
(-1550 3900);
DISPLAY 0.617021 (-1550 3900);
PAINT SKYBLUE (-1550 3900);
FORCEPROP 1 LAST VALUE 1.0UF
J 0
(-1550 4000);
DISPLAY 0.617021 (-1550 4000);
PAINT SKYBLUE (-1550 4000);
FORCEPROP 1 LASTPIN (-1600 4050) $PN 1
J 0
(-1590 4030);
DISPLAY 0.617021 (-1590 4030);
PAINT ORANGE (-1590 4030);
FORCEPROP 1 LAST PART_NUMBER D97712-004
J 0
(-1550 3800);
DISPLAY 0.617021 (-1550 3800);
PAINT BLUE (-1550 3800);
FORCEPROP 0 LAST GROUP PWR_MCP_CAP
J 0
(-1560 3701);
DISPLAY 0.638298 (-1560 3701);
PAINT BROWN (-1560 3701);
DISPLAY BOTH (-1560 3701);
FORCEPROP 2 LAST CDS_LOCATION C3C1
J 0
(-1550 4050);
DISPLAY 0.617021 (-1550 4050);
PAINT AQUA (-1550 4050);
DISPLAY INVISIBLE (-1550 4050);
FORCEPROP 2 LAST CDS_LIB dev_discrete
J 2
(-1600 3950);
PAINT ORANGE (-1600 3950);
DISPLAY INVISIBLE (-1600 3950);
FORCEPROP 2 LAST CDS_SEC 1
J 2
(-1550 4100);
PAINT ORANGE (-1550 4100);
DISPLAY INVISIBLE (-1550 4100);
FORCEPROP 2 LAST SEC_TYPE 0402V
J 2
(-1550 4150);
DISPLAY 1.021277 (-1550 4150);
PAINT ORANGE (-1550 4150);
DISPLAY INVISIBLE (-1550 4150);
FORCEPROP 2 LAST SEC 1
J 2
(-1550 4150);
DISPLAY 0.680851 (-1550 4150);
PAINT MONO (-1550 4150);
DISPLAY INVISIBLE (-1550 4150);
FORCEPROP 1 LAST PATH I38
J 0
(-1550 4100);
DISPLAY 0.978723 (-1550 4100);
PAINT WHITE (-1550 4100);
DISPLAY INVISIBLE (-1550 4100);
FORCEPROP 2 LAST ROOM P0V95_FPGA_CPU1
J 0
(-1550 4100);
DISPLAY 1.659574 (-1550 4100);
PAINT WHITE (-1550 4100);
DISPLAY INVISIBLE (-1550 4100);
FORCEADD OFFPAGE..3
(-5150 1925);
FORCEPROP 2 LAST $XR11 235 
J 0
(-4576 1889);
DISPLAY 0.638298 (-4576 1889);
PAINT MONO (-4576 1889);
FORCEPROP 2 LAST $XR10 226 
J 0
(-4696 1889);
DISPLAY 0.638298 (-4696 1889);
PAINT MONO (-4696 1889);
FORCEPROP 2 LAST $XR9 223 
J 0
(-4816 1889);
DISPLAY 0.638298 (-4816 1889);
PAINT MONO (-4816 1889);
FORCEPROP 2 LAST $XR8 218 
J 0
(-4936 1889);
DISPLAY 0.638298 (-4936 1889);
PAINT MONO (-4936 1889);
FORCEPROP 2 LAST $XR7 215 
J 0
(-4096 1925);
DISPLAY 0.638298 (-4096 1925);
PAINT MONO (-4096 1925);
FORCEPROP 2 LAST $XR6 213 
J 0
(-4216 1925);
DISPLAY 0.638298 (-4216 1925);
PAINT MONO (-4216 1925);
FORCEPROP 2 LAST $XR5 211 
J 0
(-4336 1925);
DISPLAY 0.638298 (-4336 1925);
PAINT MONO (-4336 1925);
FORCEPROP 2 LAST $XR4 206 
J 0
(-4456 1925);
DISPLAY 0.638298 (-4456 1925);
PAINT MONO (-4456 1925);
FORCEPROP 2 LAST $XR3 201 
J 0
(-4576 1925);
DISPLAY 0.638298 (-4576 1925);
PAINT MONO (-4576 1925);
FORCEPROP 2 LAST $XR2 194 
J 0
(-4696 1925);
DISPLAY 0.638298 (-4696 1925);
PAINT MONO (-4696 1925);
FORCEPROP 2 LAST $XR1 159 
J 0
(-4816 1925);
DISPLAY 0.638298 (-4816 1925);
PAINT MONO (-4816 1925);
FORCEPROP 2 LAST $XR0 138 
J 0
(-4936 1925);
DISPLAY 0.638298 (-4936 1925);
PAINT MONO (-4936 1925);
FORCEPROP 2 LAST PATH I4
J 0
(-4325 1975);
DISPLAY 1.021277 (-4325 1975);
PAINT ORANGE (-4325 1975);
DISPLAY INVISIBLE (-4325 1975);
FORCEPROP 2 LAST CDS_LIB mstr_standard
J 0
(-5150 1925);
PAINT ORANGE (-5150 1925);
DISPLAY INVISIBLE (-5150 1925);
FORCEPROP 2 LAST ROOM P0V95_FPGA_CPU0_VR
J 0
(-5550 2000);
DISPLAY 1.361702 (-5550 2000);
PAINT ORANGE (-5550 2000);
DISPLAY INVISIBLE (-5550 2000);
FORCEPROP 1 LAST OFFPAGE TRUE
J 0
(-4825 1800);
DISPLAY 1.170213 (-4825 1800);
PAINT GREEN (-4825 1800);
DISPLAY INVISIBLE (-4825 1800);
FORCEPROP 1 LAST COMMENT_BODY TRUE
J 0
(-5200 1825);
DISPLAY 1.170213 (-5200 1825);
PAINT GREEN (-5200 1825);
DISPLAY INVISIBLE (-5200 1825);
FORCEADD SCONN120_H61426002..1
(-3150 2800);
FORCEPROP 2 LASTPIN (-3550 4300) $PN E1
J 2
(-3560 4310);
DISPLAY 0.617021 (-3560 4310);
PAINT ORANGE (-3560 4310);
FORCEPROP 2 LASTPIN (-3550 1250) $PN C10
J 2
(-3560 1260);
DISPLAY 0.617021 (-3560 1260);
PAINT ORANGE (-3560 1260);
FORCEPROP 2 LASTPIN (-2750 4300) $PN E11
J 0
(-2740 4310);
DISPLAY 0.617021 (-2740 4310);
PAINT ORANGE (-2740 4310);
FORCEPROP 2 LASTPIN (-2750 4250) $PN F11
J 0
(-2740 4260);
DISPLAY 0.617021 (-2740 4260);
PAINT ORANGE (-2740 4260);
FORCEPROP 2 LASTPIN (-2750 4150) $PN A12
J 0
(-2740 4160);
DISPLAY 0.617021 (-2740 4160);
PAINT ORANGE (-2740 4160);
FORCEPROP 2 LASTPIN (-3550 4400) $PN C1
J 2
(-3560 4410);
DISPLAY 0.617021 (-3560 4410);
PAINT ORANGE (-3560 4410);
FORCEPROP 2 LASTPIN (-3550 4250) $PN F1
J 2
(-3560 4260);
DISPLAY 0.617021 (-3560 4260);
PAINT ORANGE (-3560 4260);
FORCEPROP 2 LASTPIN (-3550 3800) $PN A3
J 2
(-3560 3810);
DISPLAY 0.617021 (-3560 3810);
PAINT ORANGE (-3560 3810);
FORCEPROP 2 LASTPIN (-3550 3700) $PN C3
J 2
(-3560 3710);
DISPLAY 0.617021 (-3560 3710);
PAINT ORANGE (-3560 3710);
FORCEPROP 2 LASTPIN (-3550 3650) $PN D3
J 2
(-3560 3660);
DISPLAY 0.617021 (-3560 3660);
PAINT ORANGE (-3560 3660);
FORCEPROP 2 LASTPIN (-2750 3550) $PN F13
J 0
(-2740 3560);
DISPLAY 0.617021 (-2740 3560);
PAINT ORANGE (-2740 3560);
FORCEPROP 2 LASTPIN (-2750 4050) $PN C12
J 0
(-2740 4060);
DISPLAY 0.617021 (-2740 4060);
PAINT ORANGE (-2740 4060);
FORCEPROP 2 LASTPIN (-3550 1500) $PN E9
J 2
(-3560 1510);
DISPLAY 0.617021 (-3560 1510);
PAINT ORANGE (-3560 1510);
FORCEPROP 2 LASTPIN (-3550 1450) $PN F9
J 2
(-3560 1460);
DISPLAY 0.617021 (-3560 1460);
PAINT ORANGE (-3560 1460);
FORCEPROP 2 LASTPIN (-3550 3100) $PN A5
J 2
(-3560 3110);
DISPLAY 0.617021 (-3560 3110);
PAINT ORANGE (-3560 3110);
FORCEPROP 2 LASTPIN (-3550 1950) $PN C8
J 2
(-3560 1960);
DISPLAY 0.617021 (-3560 1960);
PAINT ORANGE (-3560 1960);
FORCEPROP 2 LASTPIN (-2750 1850) $PN E18
J 0
(-2740 1860);
DISPLAY 0.617021 (-2740 1860);
PAINT ORANGE (-2740 1860);
FORCEPROP 2 LASTPIN (-3550 4500) $PN A1
J 2
(-3560 4510);
DISPLAY 0.617021 (-3560 4510);
PAINT ORANGE (-3560 4510);
FORCEPROP 2 LASTPIN (-3550 4150) $PN A2
J 2
(-3560 4160);
DISPLAY 0.617021 (-3560 4160);
PAINT ORANGE (-3560 4160);
FORCEPROP 2 LASTPIN (-3550 3450) $PN A4
J 2
(-3560 3460);
DISPLAY 0.617021 (-3560 3460);
PAINT ORANGE (-3560 3460);
FORCEPROP 2 LASTPIN (-3550 2750) $PN A6
J 2
(-3560 2760);
DISPLAY 0.617021 (-3560 2760);
PAINT ORANGE (-3560 2760);
FORCEPROP 2 LASTPIN (-3550 2400) $PN A7
J 2
(-3560 2410);
DISPLAY 0.617021 (-3560 2410);
PAINT ORANGE (-3560 2410);
FORCEPROP 2 LASTPIN (-3550 2050) $PN A8
J 2
(-3560 2060);
DISPLAY 0.617021 (-3560 2060);
PAINT ORANGE (-3560 2060);
FORCEPROP 2 LASTPIN (-3550 1700) $PN A9
J 2
(-3560 1710);
DISPLAY 0.617021 (-3560 1710);
PAINT ORANGE (-3560 1710);
FORCEPROP 2 LASTPIN (-3550 1350) $PN A10
J 2
(-3560 1360);
DISPLAY 0.617021 (-3560 1360);
PAINT ORANGE (-3560 1360);
FORCEPROP 2 LASTPIN (-2750 4500) $PN A11
J 0
(-2740 4510);
DISPLAY 0.617021 (-2740 4510);
PAINT ORANGE (-2740 4510);
FORCEPROP 2 LASTPIN (-2750 3800) $PN A13
J 0
(-2740 3810);
DISPLAY 0.617021 (-2740 3810);
PAINT ORANGE (-2740 3810);
FORCEPROP 2 LASTPIN (-2750 3450) $PN A14
J 0
(-2740 3460);
DISPLAY 0.617021 (-2740 3460);
PAINT ORANGE (-2740 3460);
FORCEPROP 2 LASTPIN (-2750 3100) $PN A15
J 0
(-2740 3110);
DISPLAY 0.617021 (-2740 3110);
PAINT ORANGE (-2740 3110);
FORCEPROP 2 LASTPIN (-2750 2750) $PN A16
J 0
(-2740 2760);
DISPLAY 0.617021 (-2740 2760);
PAINT ORANGE (-2740 2760);
FORCEPROP 2 LASTPIN (-2750 2400) $PN A17
J 0
(-2740 2410);
DISPLAY 0.617021 (-2740 2410);
PAINT ORANGE (-2740 2410);
FORCEPROP 2 LASTPIN (-2750 2050) $PN A18
J 0
(-2740 2060);
DISPLAY 0.617021 (-2740 2060);
PAINT ORANGE (-2740 2060);
FORCEPROP 2 LASTPIN (-2750 1700) $PN A19
J 0
(-2740 1710);
DISPLAY 0.617021 (-2740 1710);
PAINT ORANGE (-2740 1710);
FORCEPROP 2 LASTPIN (-3550 4450) $PN B1
J 2
(-3560 4460);
DISPLAY 0.617021 (-3560 4460);
PAINT ORANGE (-3560 4460);
FORCEPROP 2 LASTPIN (-3550 4100) $PN B2
J 2
(-3560 4110);
DISPLAY 0.617021 (-3560 4110);
PAINT ORANGE (-3560 4110);
FORCEPROP 2 LASTPIN (-3550 3750) $PN B3
J 2
(-3560 3760);
DISPLAY 0.617021 (-3560 3760);
PAINT ORANGE (-3560 3760);
FORCEPROP 2 LASTPIN (-3550 3400) $PN B4
J 2
(-3560 3410);
DISPLAY 0.617021 (-3560 3410);
PAINT ORANGE (-3560 3410);
FORCEPROP 2 LASTPIN (-3550 3050) $PN B5
J 2
(-3560 3060);
DISPLAY 0.617021 (-3560 3060);
PAINT ORANGE (-3560 3060);
FORCEPROP 2 LASTPIN (-3550 2700) $PN B6
J 2
(-3560 2710);
DISPLAY 0.617021 (-3560 2710);
PAINT ORANGE (-3560 2710);
FORCEPROP 2 LASTPIN (-3550 2350) $PN B7
J 2
(-3560 2360);
DISPLAY 0.617021 (-3560 2360);
PAINT ORANGE (-3560 2360);
FORCEPROP 2 LASTPIN (-3550 2000) $PN B8
J 2
(-3560 2010);
DISPLAY 0.617021 (-3560 2010);
PAINT ORANGE (-3560 2010);
FORCEPROP 2 LASTPIN (-3550 1650) $PN B9
J 2
(-3560 1660);
DISPLAY 0.617021 (-3560 1660);
PAINT ORANGE (-3560 1660);
FORCEPROP 2 LASTPIN (-3550 1300) $PN B10
J 2
(-3560 1310);
DISPLAY 0.617021 (-3560 1310);
PAINT ORANGE (-3560 1310);
FORCEPROP 2 LASTPIN (-2750 4450) $PN B11
J 0
(-2740 4460);
DISPLAY 0.617021 (-2740 4460);
PAINT ORANGE (-2740 4460);
FORCEPROP 2 LASTPIN (-2750 4100) $PN B12
J 0
(-2740 4110);
DISPLAY 0.617021 (-2740 4110);
PAINT ORANGE (-2740 4110);
FORCEPROP 2 LASTPIN (-2750 3750) $PN B13
J 0
(-2740 3760);
DISPLAY 0.617021 (-2740 3760);
PAINT ORANGE (-2740 3760);
FORCEPROP 2 LASTPIN (-2750 3400) $PN B14
J 0
(-2740 3410);
DISPLAY 0.617021 (-2740 3410);
PAINT ORANGE (-2740 3410);
FORCEPROP 2 LASTPIN (-2750 3050) $PN B15
J 0
(-2740 3060);
DISPLAY 0.617021 (-2740 3060);
PAINT ORANGE (-2740 3060);
FORCEPROP 2 LASTPIN (-2750 2700) $PN B16
J 0
(-2740 2710);
DISPLAY 0.617021 (-2740 2710);
PAINT ORANGE (-2740 2710);
FORCEPROP 2 LASTPIN (-2750 2350) $PN B17
J 0
(-2740 2360);
DISPLAY 0.617021 (-2740 2360);
PAINT ORANGE (-2740 2360);
FORCEPROP 2 LASTPIN (-2750 2000) $PN B18
J 0
(-2740 2010);
DISPLAY 0.617021 (-2740 2010);
PAINT ORANGE (-2740 2010);
FORCEPROP 2 LASTPIN (-2750 1650) $PN B19
J 0
(-2740 1660);
DISPLAY 0.617021 (-2740 1660);
PAINT ORANGE (-2740 1660);
FORCEPROP 2 LASTPIN (-3550 4050) $PN C2
J 2
(-3560 4060);
DISPLAY 0.617021 (-3560 4060);
PAINT ORANGE (-3560 4060);
FORCEPROP 2 LASTPIN (-3550 3350) $PN C4
J 2
(-3560 3360);
DISPLAY 0.617021 (-3560 3360);
PAINT ORANGE (-3560 3360);
FORCEPROP 2 LASTPIN (-3550 3000) $PN C5
J 2
(-3560 3010);
DISPLAY 0.617021 (-3560 3010);
PAINT ORANGE (-3560 3010);
FORCEPROP 2 LASTPIN (-3550 2650) $PN C6
J 2
(-3560 2660);
DISPLAY 0.617021 (-3560 2660);
PAINT ORANGE (-3560 2660);
FORCEPROP 2 LASTPIN (-3550 2300) $PN C7
J 2
(-3560 2310);
DISPLAY 0.617021 (-3560 2310);
PAINT ORANGE (-3560 2310);
FORCEPROP 2 LASTPIN (-3550 1600) $PN C9
J 2
(-3560 1610);
DISPLAY 0.617021 (-3560 1610);
PAINT ORANGE (-3560 1610);
FORCEPROP 2 LASTPIN (-2750 4400) $PN C11
J 0
(-2740 4410);
DISPLAY 0.617021 (-2740 4410);
PAINT ORANGE (-2740 4410);
FORCEPROP 2 LASTPIN (-2750 3700) $PN C13
J 0
(-2740 3710);
DISPLAY 0.617021 (-2740 3710);
PAINT ORANGE (-2740 3710);
FORCEPROP 2 LASTPIN (-2750 3350) $PN C14
J 0
(-2740 3360);
DISPLAY 0.617021 (-2740 3360);
PAINT ORANGE (-2740 3360);
FORCEPROP 2 LASTPIN (-2750 3000) $PN C15
J 0
(-2740 3010);
DISPLAY 0.617021 (-2740 3010);
PAINT ORANGE (-2740 3010);
FORCEPROP 2 LASTPIN (-2750 2650) $PN C16
J 0
(-2740 2660);
DISPLAY 0.617021 (-2740 2660);
PAINT ORANGE (-2740 2660);
FORCEPROP 2 LASTPIN (-2750 2300) $PN C17
J 0
(-2740 2310);
DISPLAY 0.617021 (-2740 2310);
PAINT ORANGE (-2740 2310);
FORCEPROP 2 LASTPIN (-2750 1950) $PN C18
J 0
(-2740 1960);
DISPLAY 0.617021 (-2740 1960);
PAINT ORANGE (-2740 1960);
FORCEPROP 2 LASTPIN (-2750 1600) $PN C19
J 0
(-2740 1610);
DISPLAY 0.617021 (-2740 1610);
PAINT ORANGE (-2740 1610);
FORCEPROP 2 LASTPIN (-3550 4350) $PN D1
J 2
(-3560 4360);
DISPLAY 0.617021 (-3560 4360);
PAINT ORANGE (-3560 4360);
FORCEPROP 2 LASTPIN (-3550 4000) $PN D2
J 2
(-3560 4010);
DISPLAY 0.617021 (-3560 4010);
PAINT ORANGE (-3560 4010);
FORCEPROP 2 LASTPIN (-3550 3300) $PN D4
J 2
(-3560 3310);
DISPLAY 0.617021 (-3560 3310);
PAINT ORANGE (-3560 3310);
FORCEPROP 2 LASTPIN (-3550 2950) $PN D5
J 2
(-3560 2960);
DISPLAY 0.617021 (-3560 2960);
PAINT ORANGE (-3560 2960);
FORCEPROP 2 LASTPIN (-3550 2600) $PN D6
J 2
(-3560 2610);
DISPLAY 0.617021 (-3560 2610);
PAINT ORANGE (-3560 2610);
FORCEPROP 2 LASTPIN (-3550 2250) $PN D7
J 2
(-3560 2260);
DISPLAY 0.617021 (-3560 2260);
PAINT ORANGE (-3560 2260);
FORCEPROP 2 LASTPIN (-3550 1900) $PN D8
J 2
(-3560 1910);
DISPLAY 0.617021 (-3560 1910);
PAINT ORANGE (-3560 1910);
FORCEPROP 2 LASTPIN (-3550 1550) $PN D9
J 2
(-3560 1560);
DISPLAY 0.617021 (-3560 1560);
PAINT ORANGE (-3560 1560);
FORCEPROP 2 LASTPIN (-3550 1200) $PN D10
J 2
(-3560 1210);
DISPLAY 0.617021 (-3560 1210);
PAINT ORANGE (-3560 1210);
FORCEPROP 2 LASTPIN (-2750 4350) $PN D11
J 0
(-2740 4360);
DISPLAY 0.617021 (-2740 4360);
PAINT ORANGE (-2740 4360);
FORCEPROP 2 LASTPIN (-2750 4000) $PN D12
J 0
(-2740 4010);
DISPLAY 0.617021 (-2740 4010);
PAINT ORANGE (-2740 4010);
FORCEPROP 2 LASTPIN (-2750 3650) $PN D13
J 0
(-2740 3660);
DISPLAY 0.617021 (-2740 3660);
PAINT ORANGE (-2740 3660);
FORCEPROP 2 LASTPIN (-2750 3300) $PN D14
J 0
(-2740 3310);
DISPLAY 0.617021 (-2740 3310);
PAINT ORANGE (-2740 3310);
FORCEPROP 2 LASTPIN (-2750 2950) $PN D15
J 0
(-2740 2960);
DISPLAY 0.617021 (-2740 2960);
PAINT ORANGE (-2740 2960);
FORCEPROP 2 LASTPIN (-2750 2600) $PN D16
J 0
(-2740 2610);
DISPLAY 0.617021 (-2740 2610);
PAINT ORANGE (-2740 2610);
FORCEPROP 2 LASTPIN (-2750 2250) $PN D17
J 0
(-2740 2260);
DISPLAY 0.617021 (-2740 2260);
PAINT ORANGE (-2740 2260);
FORCEPROP 2 LASTPIN (-2750 1900) $PN D18
J 0
(-2740 1910);
DISPLAY 0.617021 (-2740 1910);
PAINT ORANGE (-2740 1910);
FORCEPROP 2 LASTPIN (-2750 1550) $PN D19
J 0
(-2740 1560);
DISPLAY 0.617021 (-2740 1560);
PAINT ORANGE (-2740 1560);
FORCEPROP 2 LASTPIN (-3550 3950) $PN E2
J 2
(-3560 3960);
DISPLAY 0.617021 (-3560 3960);
PAINT ORANGE (-3560 3960);
FORCEPROP 2 LASTPIN (-3550 3600) $PN E3
J 2
(-3560 3610);
DISPLAY 0.617021 (-3560 3610);
PAINT ORANGE (-3560 3610);
FORCEPROP 2 LASTPIN (-3550 3250) $PN E4
J 2
(-3560 3260);
DISPLAY 0.617021 (-3560 3260);
PAINT ORANGE (-3560 3260);
FORCEPROP 2 LASTPIN (-3550 2900) $PN E5
J 2
(-3560 2910);
DISPLAY 0.617021 (-3560 2910);
PAINT ORANGE (-3560 2910);
FORCEPROP 2 LASTPIN (-3550 2550) $PN E6
J 2
(-3560 2560);
DISPLAY 0.617021 (-3560 2560);
PAINT ORANGE (-3560 2560);
FORCEPROP 2 LASTPIN (-3550 2200) $PN E7
J 2
(-3560 2210);
DISPLAY 0.617021 (-3560 2210);
PAINT ORANGE (-3560 2210);
FORCEPROP 2 LASTPIN (-3550 1850) $PN E8
J 2
(-3560 1860);
DISPLAY 0.617021 (-3560 1860);
PAINT ORANGE (-3560 1860);
FORCEPROP 2 LASTPIN (-3550 1150) $PN E10
J 2
(-3560 1160);
DISPLAY 0.617021 (-3560 1160);
PAINT ORANGE (-3560 1160);
FORCEPROP 2 LASTPIN (-2750 3950) $PN E12
J 0
(-2740 3960);
DISPLAY 0.617021 (-2740 3960);
PAINT ORANGE (-2740 3960);
FORCEPROP 2 LASTPIN (-2750 3600) $PN E13
J 0
(-2740 3610);
DISPLAY 0.617021 (-2740 3610);
PAINT ORANGE (-2740 3610);
FORCEPROP 2 LASTPIN (-2750 3250) $PN E14
J 0
(-2740 3260);
DISPLAY 0.617021 (-2740 3260);
PAINT ORANGE (-2740 3260);
FORCEPROP 2 LASTPIN (-2750 2900) $PN E15
J 0
(-2740 2910);
DISPLAY 0.617021 (-2740 2910);
PAINT ORANGE (-2740 2910);
FORCEPROP 2 LASTPIN (-2750 2550) $PN E16
J 0
(-2740 2560);
DISPLAY 0.617021 (-2740 2560);
PAINT ORANGE (-2740 2560);
FORCEPROP 2 LASTPIN (-2750 2200) $PN E17
J 0
(-2740 2210);
DISPLAY 0.617021 (-2740 2210);
PAINT ORANGE (-2740 2210);
FORCEPROP 2 LASTPIN (-3550 3900) $PN F2
J 2
(-3560 3910);
DISPLAY 0.617021 (-3560 3910);
PAINT ORANGE (-3560 3910);
FORCEPROP 2 LASTPIN (-3550 3550) $PN F3
J 2
(-3560 3560);
DISPLAY 0.617021 (-3560 3560);
PAINT ORANGE (-3560 3560);
FORCEPROP 2 LASTPIN (-3550 3200) $PN F4
J 2
(-3560 3210);
DISPLAY 0.617021 (-3560 3210);
PAINT ORANGE (-3560 3210);
FORCEPROP 2 LASTPIN (-3550 2850) $PN F5
J 2
(-3560 2860);
DISPLAY 0.617021 (-3560 2860);
PAINT ORANGE (-3560 2860);
FORCEPROP 2 LASTPIN (-3550 2500) $PN F6
J 2
(-3560 2510);
DISPLAY 0.617021 (-3560 2510);
PAINT ORANGE (-3560 2510);
FORCEPROP 2 LASTPIN (-3550 2150) $PN F7
J 2
(-3560 2160);
DISPLAY 0.617021 (-3560 2160);
PAINT ORANGE (-3560 2160);
FORCEPROP 2 LASTPIN (-3550 1800) $PN F8
J 2
(-3560 1810);
DISPLAY 0.617021 (-3560 1810);
PAINT ORANGE (-3560 1810);
FORCEPROP 2 LASTPIN (-3550 1100) $PN F10
J 2
(-3560 1110);
DISPLAY 0.617021 (-3560 1110);
PAINT ORANGE (-3560 1110);
FORCEPROP 2 LASTPIN (-2750 3900) $PN F12
J 0
(-2740 3910);
DISPLAY 0.617021 (-2740 3910);
PAINT ORANGE (-2740 3910);
FORCEPROP 2 LASTPIN (-2750 3200) $PN F14
J 0
(-2740 3210);
DISPLAY 0.617021 (-2740 3210);
PAINT ORANGE (-2740 3210);
FORCEPROP 2 LASTPIN (-2750 2850) $PN F15
J 0
(-2740 2860);
DISPLAY 0.617021 (-2740 2860);
PAINT ORANGE (-2740 2860);
FORCEPROP 2 LASTPIN (-2750 2500) $PN F16
J 0
(-2740 2510);
DISPLAY 0.617021 (-2740 2510);
PAINT ORANGE (-2740 2510);
FORCEPROP 2 LASTPIN (-2750 2150) $PN F17
J 0
(-2740 2160);
DISPLAY 0.617021 (-2740 2160);
PAINT ORANGE (-2740 2160);
FORCEPROP 2 LASTPIN (-2750 1800) $PN F18
J 0
(-2740 1810);
DISPLAY 0.617021 (-2740 1810);
PAINT ORANGE (-2740 1810);
FORCEPROP 2 LASTPIN (-2750 1450) $PN F19
J 0
(-2740 1460);
DISPLAY 0.617021 (-2740 1460);
PAINT ORANGE (-2740 1460);
FORCEPROP 1 LAST MATERIAL CONN
J 0
(-3500 4750);
DISPLAY 0.617021 (-3500 4750);
PAINT SKYBLUE (-3500 4750);
FORCEPROP 1 LAST LOCATION J4E1
J 0
(-3500 4800);
DISPLAY 0.617021 (-3500 4800);
PAINT AQUA (-3500 4800);
FORCEPROP 2 LASTPIN (-2750 1500) $PN E19
J 0
(-2740 1510);
DISPLAY 0.617021 (-2740 1510);
PAINT ORANGE (-2740 1510);
FORCEPROP 0 LAST GROUP MCP
J 0
(-3491 849);
DISPLAY 0.638298 (-3491 849);
PAINT BROWN (-3491 849);
DISPLAY BOTH (-3491 849);
FORCEPROP 1 LAST PART_NUMBER H61426-002
J 0
(-3500 900);
DISPLAY 0.617021 (-3500 900);
PAINT BLUE (-3500 900);
FORCEPROP 2 LASTPIN (-2750 1100) $PN F20
J 0
(-2740 1110);
DISPLAY 0.617021 (-2740 1110);
PAINT ORANGE (-2740 1110);
FORCEPROP 2 LASTPIN (-2750 1150) $PN E20
J 0
(-2740 1160);
DISPLAY 0.617021 (-2740 1160);
PAINT ORANGE (-2740 1160);
FORCEPROP 2 LASTPIN (-2750 1200) $PN D20
J 0
(-2740 1210);
DISPLAY 0.617021 (-2740 1210);
PAINT ORANGE (-2740 1210);
FORCEPROP 2 LASTPIN (-2750 1250) $PN C20
J 0
(-2740 1260);
DISPLAY 0.617021 (-2740 1260);
PAINT ORANGE (-2740 1260);
FORCEPROP 2 LASTPIN (-2750 1300) $PN B20
J 0
(-2740 1310);
DISPLAY 0.617021 (-2740 1310);
PAINT ORANGE (-2740 1310);
FORCEPROP 2 LASTPIN (-2750 1350) $PN A20
J 0
(-2740 1360);
DISPLAY 0.617021 (-2740 1360);
PAINT ORANGE (-2740 1360);
FORCEPROP 0 LAST ROOM MCP VRM CPU1
J 0
(-3500 4900);
DISPLAY 1.021277 (-3500 4900);
PAINT ORANGE (-3500 4900);
DISPLAY INVISIBLE (-3500 4900);
FORCEPROP 1 LAST PATH I45
J 0
(-3100 4750);
PAINT GREEN (-3100 4750);
DISPLAY INVISIBLE (-3100 4750);
FORCEPROP 2 LAST CDS_LOCATION J4E1
J 0
(-3500 4800);
DISPLAY 0.617021 (-3500 4800);
PAINT AQUA (-3500 4800);
DISPLAY INVISIBLE (-3500 4800);
FORCEPROP 2 LAST SEC 1
J 0
(-3500 4850);
DISPLAY 0.680851 (-3500 4850);
PAINT MONO (-3500 4850);
DISPLAY INVISIBLE (-3500 4850);
FORCEPROP 2 LAST SEC_TYPE SM
J 0
(-3500 4850);
DISPLAY 1.021277 (-3500 4850);
PAINT ORANGE (-3500 4850);
DISPLAY INVISIBLE (-3500 4850);
FORCEPROP 2 LAST CDS_LIB mstr_sconn
J 0
(-3150 2800);
PAINT ORANGE (-3150 2800);
DISPLAY INVISIBLE (-3150 2800);
FORCEPROP 1 LAST PACK_TYPE SM
J 0
(-3500 4850);
PAINT SKYBLUE (-3500 4850);
DISPLAY INVISIBLE (-3500 4850);
FORCEADD SCONN120_H61426002..1
(-6325 2725);
FORCEPROP 2 LASTPIN (-6725 1975) $PN A8
J 2
(-6735 1985);
DISPLAY 0.617021 (-6735 1985);
PAINT ORANGE (-6735 1985);
FORCEPROP 2 LASTPIN (-6725 4075) $PN A2
J 2
(-6735 4085);
DISPLAY 0.617021 (-6735 4085);
PAINT ORANGE (-6735 4085);
FORCEPROP 2 LASTPIN (-5925 3925) $PN D12
J 0
(-5915 3935);
DISPLAY 0.617021 (-5915 3935);
PAINT ORANGE (-5915 3935);
FORCEPROP 2 LASTPIN (-5925 3875) $PN E12
J 0
(-5915 3885);
DISPLAY 0.617021 (-5915 3885);
PAINT ORANGE (-5915 3885);
FORCEPROP 2 LASTPIN (-5925 3825) $PN F12
J 0
(-5915 3835);
DISPLAY 0.617021 (-5915 3835);
PAINT ORANGE (-5915 3835);
FORCEPROP 2 LASTPIN (-5925 1025) $PN F20
J 0
(-5915 1035);
DISPLAY 0.617021 (-5915 1035);
PAINT ORANGE (-5915 1035);
FORCEPROP 1 LAST PART_NUMBER H61426-002
J 0
(-6675 825);
DISPLAY 0.617021 (-6675 825);
PAINT BLUE (-6675 825);
FORCEPROP 0 LAST GROUP MCP
J 0
(-6660 785);
DISPLAY 0.638298 (-6660 785);
PAINT BROWN (-6660 785);
DISPLAY BOTH (-6660 785);
FORCEPROP 2 LASTPIN (-5925 4425) $PN A11
J 0
(-5915 4435);
DISPLAY 0.617021 (-5915 4435);
PAINT ORANGE (-5915 4435);
FORCEPROP 2 LASTPIN (-5925 1725) $PN F18
J 0
(-5915 1735);
DISPLAY 0.617021 (-5915 1735);
PAINT ORANGE (-5915 1735);
FORCEPROP 2 LASTPIN (-6725 4425) $PN A1
J 2
(-6735 4435);
DISPLAY 0.617021 (-6735 4435);
PAINT ORANGE (-6735 4435);
FORCEPROP 2 LASTPIN (-6725 3725) $PN A3
J 2
(-6735 3735);
DISPLAY 0.617021 (-6735 3735);
PAINT ORANGE (-6735 3735);
FORCEPROP 2 LASTPIN (-6725 3375) $PN A4
J 2
(-6735 3385);
DISPLAY 0.617021 (-6735 3385);
PAINT ORANGE (-6735 3385);
FORCEPROP 2 LASTPIN (-6725 3025) $PN A5
J 2
(-6735 3035);
DISPLAY 0.617021 (-6735 3035);
PAINT ORANGE (-6735 3035);
FORCEPROP 2 LASTPIN (-6725 2675) $PN A6
J 2
(-6735 2685);
DISPLAY 0.617021 (-6735 2685);
PAINT ORANGE (-6735 2685);
FORCEPROP 2 LASTPIN (-6725 2325) $PN A7
J 2
(-6735 2335);
DISPLAY 0.617021 (-6735 2335);
PAINT ORANGE (-6735 2335);
FORCEPROP 2 LASTPIN (-6725 1625) $PN A9
J 2
(-6735 1635);
DISPLAY 0.617021 (-6735 1635);
PAINT ORANGE (-6735 1635);
FORCEPROP 2 LASTPIN (-6725 1275) $PN A10
J 2
(-6735 1285);
DISPLAY 0.617021 (-6735 1285);
PAINT ORANGE (-6735 1285);
FORCEPROP 2 LASTPIN (-5925 4075) $PN A12
J 0
(-5915 4085);
DISPLAY 0.617021 (-5915 4085);
PAINT ORANGE (-5915 4085);
FORCEPROP 2 LASTPIN (-5925 3725) $PN A13
J 0
(-5915 3735);
DISPLAY 0.617021 (-5915 3735);
PAINT ORANGE (-5915 3735);
FORCEPROP 2 LASTPIN (-5925 3025) $PN A15
J 0
(-5915 3035);
DISPLAY 0.617021 (-5915 3035);
PAINT ORANGE (-5915 3035);
FORCEPROP 2 LASTPIN (-5925 2325) $PN A17
J 0
(-5915 2335);
DISPLAY 0.617021 (-5915 2335);
PAINT ORANGE (-5915 2335);
FORCEPROP 2 LASTPIN (-5925 1975) $PN A18
J 0
(-5915 1985);
DISPLAY 0.617021 (-5915 1985);
PAINT ORANGE (-5915 1985);
FORCEPROP 2 LASTPIN (-5925 1625) $PN A19
J 0
(-5915 1635);
DISPLAY 0.617021 (-5915 1635);
PAINT ORANGE (-5915 1635);
FORCEPROP 2 LASTPIN (-5925 1275) $PN A20
J 0
(-5915 1285);
DISPLAY 0.617021 (-5915 1285);
PAINT ORANGE (-5915 1285);
FORCEPROP 2 LASTPIN (-6725 4375) $PN B1
J 2
(-6735 4385);
DISPLAY 0.617021 (-6735 4385);
PAINT ORANGE (-6735 4385);
FORCEPROP 2 LASTPIN (-6725 4025) $PN B2
J 2
(-6735 4035);
DISPLAY 0.617021 (-6735 4035);
PAINT ORANGE (-6735 4035);
FORCEPROP 2 LASTPIN (-6725 3675) $PN B3
J 2
(-6735 3685);
DISPLAY 0.617021 (-6735 3685);
PAINT ORANGE (-6735 3685);
FORCEPROP 2 LASTPIN (-6725 3325) $PN B4
J 2
(-6735 3335);
DISPLAY 0.617021 (-6735 3335);
PAINT ORANGE (-6735 3335);
FORCEPROP 2 LASTPIN (-6725 2975) $PN B5
J 2
(-6735 2985);
DISPLAY 0.617021 (-6735 2985);
PAINT ORANGE (-6735 2985);
FORCEPROP 2 LASTPIN (-6725 2625) $PN B6
J 2
(-6735 2635);
DISPLAY 0.617021 (-6735 2635);
PAINT ORANGE (-6735 2635);
FORCEPROP 2 LASTPIN (-6725 2275) $PN B7
J 2
(-6735 2285);
DISPLAY 0.617021 (-6735 2285);
PAINT ORANGE (-6735 2285);
FORCEPROP 2 LASTPIN (-6725 1925) $PN B8
J 2
(-6735 1935);
DISPLAY 0.617021 (-6735 1935);
PAINT ORANGE (-6735 1935);
FORCEPROP 2 LASTPIN (-6725 1575) $PN B9
J 2
(-6735 1585);
DISPLAY 0.617021 (-6735 1585);
PAINT ORANGE (-6735 1585);
FORCEPROP 2 LASTPIN (-5925 4375) $PN B11
J 0
(-5915 4385);
DISPLAY 0.617021 (-5915 4385);
PAINT ORANGE (-5915 4385);
FORCEPROP 2 LASTPIN (-5925 3675) $PN B13
J 0
(-5915 3685);
DISPLAY 0.617021 (-5915 3685);
PAINT ORANGE (-5915 3685);
FORCEPROP 2 LASTPIN (-5925 2975) $PN B15
J 0
(-5915 2985);
DISPLAY 0.617021 (-5915 2985);
PAINT ORANGE (-5915 2985);
FORCEPROP 2 LASTPIN (-5925 2275) $PN B17
J 0
(-5915 2285);
DISPLAY 0.617021 (-5915 2285);
PAINT ORANGE (-5915 2285);
FORCEPROP 2 LASTPIN (-5925 1925) $PN B18
J 0
(-5915 1935);
DISPLAY 0.617021 (-5915 1935);
PAINT ORANGE (-5915 1935);
FORCEPROP 2 LASTPIN (-5925 1575) $PN B19
J 0
(-5915 1585);
DISPLAY 0.617021 (-5915 1585);
PAINT ORANGE (-5915 1585);
FORCEPROP 2 LASTPIN (-5925 1225) $PN B20
J 0
(-5915 1235);
DISPLAY 0.617021 (-5915 1235);
PAINT ORANGE (-5915 1235);
FORCEPROP 2 LASTPIN (-6725 4325) $PN C1
J 2
(-6735 4335);
DISPLAY 0.617021 (-6735 4335);
PAINT ORANGE (-6735 4335);
FORCEPROP 2 LASTPIN (-6725 3975) $PN C2
J 2
(-6735 3985);
DISPLAY 0.617021 (-6735 3985);
PAINT ORANGE (-6735 3985);
FORCEPROP 2 LASTPIN (-6725 3625) $PN C3
J 2
(-6735 3635);
DISPLAY 0.617021 (-6735 3635);
PAINT ORANGE (-6735 3635);
FORCEPROP 2 LASTPIN (-6725 3275) $PN C4
J 2
(-6735 3285);
DISPLAY 0.617021 (-6735 3285);
PAINT ORANGE (-6735 3285);
FORCEPROP 2 LASTPIN (-6725 2925) $PN C5
J 2
(-6735 2935);
DISPLAY 0.617021 (-6735 2935);
PAINT ORANGE (-6735 2935);
FORCEPROP 2 LASTPIN (-6725 2575) $PN C6
J 2
(-6735 2585);
DISPLAY 0.617021 (-6735 2585);
PAINT ORANGE (-6735 2585);
FORCEPROP 2 LASTPIN (-6725 2225) $PN C7
J 2
(-6735 2235);
DISPLAY 0.617021 (-6735 2235);
PAINT ORANGE (-6735 2235);
FORCEPROP 2 LASTPIN (-6725 1875) $PN C8
J 2
(-6735 1885);
DISPLAY 0.617021 (-6735 1885);
PAINT ORANGE (-6735 1885);
FORCEPROP 2 LASTPIN (-6725 1525) $PN C9
J 2
(-6735 1535);
DISPLAY 0.617021 (-6735 1535);
PAINT ORANGE (-6735 1535);
FORCEPROP 2 LASTPIN (-6725 1175) $PN C10
J 2
(-6735 1185);
DISPLAY 0.617021 (-6735 1185);
PAINT ORANGE (-6735 1185);
FORCEPROP 2 LASTPIN (-5925 4325) $PN C11
J 0
(-5915 4335);
DISPLAY 0.617021 (-5915 4335);
PAINT ORANGE (-5915 4335);
FORCEPROP 2 LASTPIN (-5925 3975) $PN C12
J 0
(-5915 3985);
DISPLAY 0.617021 (-5915 3985);
PAINT ORANGE (-5915 3985);
FORCEPROP 2 LASTPIN (-5925 3625) $PN C13
J 0
(-5915 3635);
DISPLAY 0.617021 (-5915 3635);
PAINT ORANGE (-5915 3635);
FORCEPROP 2 LASTPIN (-5925 2925) $PN C15
J 0
(-5915 2935);
DISPLAY 0.617021 (-5915 2935);
PAINT ORANGE (-5915 2935);
FORCEPROP 2 LASTPIN (-5925 2225) $PN C17
J 0
(-5915 2235);
DISPLAY 0.617021 (-5915 2235);
PAINT ORANGE (-5915 2235);
FORCEPROP 2 LASTPIN (-5925 1875) $PN C18
J 0
(-5915 1885);
DISPLAY 0.617021 (-5915 1885);
PAINT ORANGE (-5915 1885);
FORCEPROP 2 LASTPIN (-5925 1525) $PN C19
J 0
(-5915 1535);
DISPLAY 0.617021 (-5915 1535);
PAINT ORANGE (-5915 1535);
FORCEPROP 2 LASTPIN (-5925 1175) $PN C20
J 0
(-5915 1185);
DISPLAY 0.617021 (-5915 1185);
PAINT ORANGE (-5915 1185);
FORCEPROP 2 LASTPIN (-6725 4275) $PN D1
J 2
(-6735 4285);
DISPLAY 0.617021 (-6735 4285);
PAINT ORANGE (-6735 4285);
FORCEPROP 2 LASTPIN (-6725 3925) $PN D2
J 2
(-6735 3935);
DISPLAY 0.617021 (-6735 3935);
PAINT ORANGE (-6735 3935);
FORCEPROP 2 LASTPIN (-6725 3575) $PN D3
J 2
(-6735 3585);
DISPLAY 0.617021 (-6735 3585);
PAINT ORANGE (-6735 3585);
FORCEPROP 2 LASTPIN (-6725 3225) $PN D4
J 2
(-6735 3235);
DISPLAY 0.617021 (-6735 3235);
PAINT ORANGE (-6735 3235);
FORCEPROP 2 LASTPIN (-6725 2875) $PN D5
J 2
(-6735 2885);
DISPLAY 0.617021 (-6735 2885);
PAINT ORANGE (-6735 2885);
FORCEPROP 2 LASTPIN (-6725 2525) $PN D6
J 2
(-6735 2535);
DISPLAY 0.617021 (-6735 2535);
PAINT ORANGE (-6735 2535);
FORCEPROP 2 LASTPIN (-6725 2175) $PN D7
J 2
(-6735 2185);
DISPLAY 0.617021 (-6735 2185);
PAINT ORANGE (-6735 2185);
FORCEPROP 2 LASTPIN (-6725 1825) $PN D8
J 2
(-6735 1835);
DISPLAY 0.617021 (-6735 1835);
PAINT ORANGE (-6735 1835);
FORCEPROP 2 LASTPIN (-6725 1475) $PN D9
J 2
(-6735 1485);
DISPLAY 0.617021 (-6735 1485);
PAINT ORANGE (-6735 1485);
FORCEPROP 2 LASTPIN (-6725 1125) $PN D10
J 2
(-6735 1135);
DISPLAY 0.617021 (-6735 1135);
PAINT ORANGE (-6735 1135);
FORCEPROP 2 LASTPIN (-5925 4275) $PN D11
J 0
(-5915 4285);
DISPLAY 0.617021 (-5915 4285);
PAINT ORANGE (-5915 4285);
FORCEPROP 2 LASTPIN (-5925 3575) $PN D13
J 0
(-5915 3585);
DISPLAY 0.617021 (-5915 3585);
PAINT ORANGE (-5915 3585);
FORCEPROP 2 LASTPIN (-5925 3225) $PN D14
J 0
(-5915 3235);
DISPLAY 0.617021 (-5915 3235);
PAINT ORANGE (-5915 3235);
FORCEPROP 2 LASTPIN (-5925 2175) $PN D17
J 0
(-5915 2185);
DISPLAY 0.617021 (-5915 2185);
PAINT ORANGE (-5915 2185);
FORCEPROP 2 LASTPIN (-5925 1825) $PN D18
J 0
(-5915 1835);
DISPLAY 0.617021 (-5915 1835);
PAINT ORANGE (-5915 1835);
FORCEPROP 2 LASTPIN (-5925 1125) $PN D20
J 0
(-5915 1135);
DISPLAY 0.617021 (-5915 1135);
PAINT ORANGE (-5915 1135);
FORCEPROP 2 LASTPIN (-6725 4225) $PN E1
J 2
(-6735 4235);
DISPLAY 0.617021 (-6735 4235);
PAINT ORANGE (-6735 4235);
FORCEPROP 2 LASTPIN (-6725 3875) $PN E2
J 2
(-6735 3885);
DISPLAY 0.617021 (-6735 3885);
PAINT ORANGE (-6735 3885);
FORCEPROP 2 LASTPIN (-6725 3525) $PN E3
J 2
(-6735 3535);
DISPLAY 0.617021 (-6735 3535);
PAINT ORANGE (-6735 3535);
FORCEPROP 2 LASTPIN (-6725 3175) $PN E4
J 2
(-6735 3185);
DISPLAY 0.617021 (-6735 3185);
PAINT ORANGE (-6735 3185);
FORCEPROP 2 LASTPIN (-6725 2825) $PN E5
J 2
(-6735 2835);
DISPLAY 0.617021 (-6735 2835);
PAINT ORANGE (-6735 2835);
FORCEPROP 2 LASTPIN (-6725 2475) $PN E6
J 2
(-6735 2485);
DISPLAY 0.617021 (-6735 2485);
PAINT ORANGE (-6735 2485);
FORCEPROP 2 LASTPIN (-6725 2125) $PN E7
J 2
(-6735 2135);
DISPLAY 0.617021 (-6735 2135);
PAINT ORANGE (-6735 2135);
FORCEPROP 2 LASTPIN (-6725 1775) $PN E8
J 2
(-6735 1785);
DISPLAY 0.617021 (-6735 1785);
PAINT ORANGE (-6735 1785);
FORCEPROP 2 LASTPIN (-6725 1425) $PN E9
J 2
(-6735 1435);
DISPLAY 0.617021 (-6735 1435);
PAINT ORANGE (-6735 1435);
FORCEPROP 2 LASTPIN (-6725 1075) $PN E10
J 2
(-6735 1085);
DISPLAY 0.617021 (-6735 1085);
PAINT ORANGE (-6735 1085);
FORCEPROP 2 LASTPIN (-5925 4225) $PN E11
J 0
(-5915 4235);
DISPLAY 0.617021 (-5915 4235);
PAINT ORANGE (-5915 4235);
FORCEPROP 2 LASTPIN (-5925 2125) $PN E17
J 0
(-5915 2135);
DISPLAY 0.617021 (-5915 2135);
PAINT ORANGE (-5915 2135);
FORCEPROP 2 LASTPIN (-5925 1775) $PN E18
J 0
(-5915 1785);
DISPLAY 0.617021 (-5915 1785);
PAINT ORANGE (-5915 1785);
FORCEPROP 2 LASTPIN (-5925 1075) $PN E20
J 0
(-5915 1085);
DISPLAY 0.617021 (-5915 1085);
PAINT ORANGE (-5915 1085);
FORCEPROP 2 LASTPIN (-6725 4175) $PN F1
J 2
(-6735 4185);
DISPLAY 0.617021 (-6735 4185);
PAINT ORANGE (-6735 4185);
FORCEPROP 2 LASTPIN (-6725 3825) $PN F2
J 2
(-6735 3835);
DISPLAY 0.617021 (-6735 3835);
PAINT ORANGE (-6735 3835);
FORCEPROP 2 LASTPIN (-6725 3475) $PN F3
J 2
(-6735 3485);
DISPLAY 0.617021 (-6735 3485);
PAINT ORANGE (-6735 3485);
FORCEPROP 2 LASTPIN (-6725 3125) $PN F4
J 2
(-6735 3135);
DISPLAY 0.617021 (-6735 3135);
PAINT ORANGE (-6735 3135);
FORCEPROP 2 LASTPIN (-6725 2775) $PN F5
J 2
(-6735 2785);
DISPLAY 0.617021 (-6735 2785);
PAINT ORANGE (-6735 2785);
FORCEPROP 2 LASTPIN (-6725 2425) $PN F6
J 2
(-6735 2435);
DISPLAY 0.617021 (-6735 2435);
PAINT ORANGE (-6735 2435);
FORCEPROP 2 LASTPIN (-6725 2075) $PN F7
J 2
(-6735 2085);
DISPLAY 0.617021 (-6735 2085);
PAINT ORANGE (-6735 2085);
FORCEPROP 2 LASTPIN (-6725 1725) $PN F8
J 2
(-6735 1735);
DISPLAY 0.617021 (-6735 1735);
PAINT ORANGE (-6735 1735);
FORCEPROP 2 LASTPIN (-6725 1375) $PN F9
J 2
(-6735 1385);
DISPLAY 0.617021 (-6735 1385);
PAINT ORANGE (-6735 1385);
FORCEPROP 2 LASTPIN (-5925 4175) $PN F11
J 0
(-5915 4185);
DISPLAY 0.617021 (-5915 4185);
PAINT ORANGE (-5915 4185);
FORCEPROP 2 LASTPIN (-5925 3475) $PN F13
J 0
(-5915 3485);
DISPLAY 0.617021 (-5915 3485);
PAINT ORANGE (-5915 3485);
FORCEPROP 2 LASTPIN (-5925 3125) $PN F14
J 0
(-5915 3135);
DISPLAY 0.617021 (-5915 3135);
PAINT ORANGE (-5915 3135);
FORCEPROP 2 LASTPIN (-5925 2425) $PN F16
J 0
(-5915 2435);
DISPLAY 0.617021 (-5915 2435);
PAINT ORANGE (-5915 2435);
FORCEPROP 2 LASTPIN (-5925 2075) $PN F17
J 0
(-5915 2085);
DISPLAY 0.617021 (-5915 2085);
PAINT ORANGE (-5915 2085);
FORCEPROP 2 LASTPIN (-5925 1375) $PN F19
J 0
(-5915 1385);
DISPLAY 0.617021 (-5915 1385);
PAINT ORANGE (-5915 1385);
FORCEPROP 1 LAST MATERIAL CONN
J 0
(-6675 4675);
DISPLAY 0.617021 (-6675 4675);
PAINT SKYBLUE (-6675 4675);
FORCEPROP 1 LAST LOCATION J4B2
J 0
(-6675 4725);
DISPLAY 0.617021 (-6675 4725);
PAINT AQUA (-6675 4725);
FORCEPROP 2 LASTPIN (-5925 3175) $PN E14
J 0
(-5915 3185);
DISPLAY 0.617021 (-5915 3185);
PAINT ORANGE (-5915 3185);
FORCEPROP 2 LASTPIN (-5925 1425) $PN E19
J 0
(-5915 1435);
DISPLAY 0.617021 (-5915 1435);
PAINT ORANGE (-5915 1435);
FORCEPROP 2 LASTPIN (-5925 1475) $PN D19
J 0
(-5915 1485);
DISPLAY 0.617021 (-5915 1485);
PAINT ORANGE (-5915 1485);
FORCEPROP 2 LASTPIN (-5925 3375) $PN A14
J 0
(-5915 3385);
DISPLAY 0.617021 (-5915 3385);
PAINT ORANGE (-5915 3385);
FORCEPROP 2 LASTPIN (-5925 3525) $PN E13
J 0
(-5915 3535);
DISPLAY 0.617021 (-5915 3535);
PAINT ORANGE (-5915 3535);
FORCEPROP 2 LASTPIN (-5925 4025) $PN B12
J 0
(-5915 4035);
DISPLAY 0.617021 (-5915 4035);
PAINT ORANGE (-5915 4035);
FORCEPROP 2 LASTPIN (-5925 3325) $PN B14
J 0
(-5915 3335);
DISPLAY 0.617021 (-5915 3335);
PAINT ORANGE (-5915 3335);
FORCEPROP 2 LASTPIN (-5925 3275) $PN C14
J 0
(-5915 3285);
DISPLAY 0.617021 (-5915 3285);
PAINT ORANGE (-5915 3285);
FORCEPROP 2 LASTPIN (-5925 2575) $PN C16
J 0
(-5915 2585);
DISPLAY 0.617021 (-5915 2585);
PAINT ORANGE (-5915 2585);
FORCEPROP 2 LASTPIN (-5925 2475) $PN E16
J 0
(-5915 2485);
DISPLAY 0.617021 (-5915 2485);
PAINT ORANGE (-5915 2485);
FORCEPROP 2 LASTPIN (-5925 2525) $PN D16
J 0
(-5915 2535);
DISPLAY 0.617021 (-5915 2535);
PAINT ORANGE (-5915 2535);
FORCEPROP 2 LASTPIN (-5925 2675) $PN A16
J 0
(-5915 2685);
DISPLAY 0.617021 (-5915 2685);
PAINT ORANGE (-5915 2685);
FORCEPROP 2 LASTPIN (-5925 2775) $PN F15
J 0
(-5915 2785);
DISPLAY 0.617021 (-5915 2785);
PAINT ORANGE (-5915 2785);
FORCEPROP 2 LASTPIN (-5925 2825) $PN E15
J 0
(-5915 2835);
DISPLAY 0.617021 (-5915 2835);
PAINT ORANGE (-5915 2835);
FORCEPROP 2 LASTPIN (-5925 2875) $PN D15
J 0
(-5915 2885);
DISPLAY 0.617021 (-5915 2885);
PAINT ORANGE (-5915 2885);
FORCEPROP 2 LASTPIN (-5925 2625) $PN B16
J 0
(-5915 2635);
DISPLAY 0.617021 (-5915 2635);
PAINT ORANGE (-5915 2635);
FORCEPROP 2 LASTPIN (-6725 1225) $PN B10
J 2
(-6735 1235);
DISPLAY 0.617021 (-6735 1235);
PAINT ORANGE (-6735 1235);
FORCEPROP 2 LASTPIN (-6725 1025) $PN F10
J 2
(-6735 1035);
DISPLAY 0.617021 (-6735 1035);
PAINT ORANGE (-6735 1035);
FORCEPROP 0 LAST ROOM MCP VRM CPU1
J 0
(-6675 4825);
DISPLAY 1.021277 (-6675 4825);
PAINT ORANGE (-6675 4825);
DISPLAY INVISIBLE (-6675 4825);
FORCEPROP 1 LAST PATH I46
J 0
(-6275 4675);
PAINT GREEN (-6275 4675);
DISPLAY INVISIBLE (-6275 4675);
FORCEPROP 2 LAST CDS_LOCATION J4B2
J 0
(-6675 4725);
DISPLAY 0.617021 (-6675 4725);
PAINT AQUA (-6675 4725);
DISPLAY INVISIBLE (-6675 4725);
FORCEPROP 2 LAST SEC 1
J 0
(-6675 4775);
DISPLAY 0.680851 (-6675 4775);
PAINT MONO (-6675 4775);
DISPLAY INVISIBLE (-6675 4775);
FORCEPROP 2 LAST SEC_TYPE SM
J 0
(-6675 4775);
DISPLAY 1.021277 (-6675 4775);
PAINT ORANGE (-6675 4775);
DISPLAY INVISIBLE (-6675 4775);
FORCEPROP 2 LAST CDS_LIB mstr_sconn
J 0
(-6325 2725);
PAINT ORANGE (-6325 2725);
DISPLAY INVISIBLE (-6325 2725);
FORCEPROP 1 LAST PACK_TYPE SM
J 0
(-6675 4775);
PAINT SKYBLUE (-6675 4775);
DISPLAY INVISIBLE (-6675 4775);
FORCEADD OFFPAGE..1
(-4825 3400);
FORCEPROP 2 LAST $XR0 73 
J 0
(-5046 3400);
DISPLAY 0.638298 (-5046 3400);
PAINT MONO (-5046 3400);
FORCEPROP 2 LAST CDS_LIB mstr_standard
J 0
(-4825 3400);
PAINT MONO (-4825 3400);
DISPLAY INVISIBLE (-4825 3400);
FORCEPROP 2 LAST PATH I49
J 0
(-4775 3475);
DISPLAY 1.021277 (-4775 3475);
PAINT ORANGE (-4775 3475);
DISPLAY INVISIBLE (-4775 3475);
FORCEPROP 1 LAST OFFPAGE TRUE
J 0
(-4500 3275);
DISPLAY 1.170213 (-4500 3275);
PAINT GREEN (-4500 3275);
DISPLAY INVISIBLE (-4500 3275);
FORCEPROP 1 LAST COMMENT_BODY TRUE
J 0
(-4700 3300);
DISPLAY 1.170213 (-4700 3300);
PAINT GREEN (-4700 3300);
DISPLAY INVISIBLE (-4700 3300);
FORCEADD OFFPAGE..1
R 2
(-5150 1975);
FORCEPROP 2 LAST $XR11 226 
J 0
(-4604 2011);
DISPLAY 0.638298 (-4604 2011);
PAINT MONO (-4604 2011);
FORCEPROP 2 LAST $XR10 223 
J 0
(-4724 2011);
DISPLAY 0.638298 (-4724 2011);
PAINT MONO (-4724 2011);
FORCEPROP 2 LAST $XR9 218 
J 0
(-4844 2011);
DISPLAY 0.638298 (-4844 2011);
PAINT MONO (-4844 2011);
FORCEPROP 2 LAST $XR8 215 
J 0
(-4964 2011);
DISPLAY 0.638298 (-4964 2011);
PAINT MONO (-4964 2011);
FORCEPROP 2 LAST $XR7 206 
J 0
(-4124 1975);
DISPLAY 0.638298 (-4124 1975);
PAINT MONO (-4124 1975);
FORCEPROP 2 LAST $XR6 201 
J 0
(-4244 1975);
DISPLAY 0.638298 (-4244 1975);
PAINT MONO (-4244 1975);
FORCEPROP 2 LAST $XR5 194 
J 0
(-4364 1975);
DISPLAY 0.638298 (-4364 1975);
PAINT MONO (-4364 1975);
FORCEPROP 2 LAST $XR4 235 
J 0
(-4484 1975);
DISPLAY 0.638298 (-4484 1975);
PAINT MONO (-4484 1975);
FORCEPROP 2 LAST $XR3 213 
J 0
(-4604 1975);
DISPLAY 0.638298 (-4604 1975);
PAINT MONO (-4604 1975);
FORCEPROP 2 LAST $XR2 211 
J 0
(-4724 1975);
DISPLAY 0.638298 (-4724 1975);
PAINT MONO (-4724 1975);
FORCEPROP 2 LAST $XR1 159 
J 0
(-4844 1975);
DISPLAY 0.638298 (-4844 1975);
PAINT MONO (-4844 1975);
FORCEPROP 2 LAST $XR0 138 
J 0
(-4964 1975);
DISPLAY 0.638298 (-4964 1975);
PAINT MONO (-4964 1975);
FORCEPROP 2 LAST PATH I5
J 0
(-4950 2100);
DISPLAY 1.021277 (-4950 2100);
PAINT ORANGE (-4950 2100);
DISPLAY INVISIBLE (-4950 2100);
FORCEPROP 2 LAST CDS_LIB mstr_standard
J 0
(-5150 1975);
PAINT ORANGE (-5150 1975);
DISPLAY INVISIBLE (-5150 1975);
FORCEPROP 2 LAST ROOM P0V95_FPGA_CPU0_VR
J 0
(-5575 2050);
DISPLAY 1.361702 (-5575 2050);
PAINT ORANGE (-5575 2050);
DISPLAY INVISIBLE (-5575 2050);
FORCEPROP 1 LAST OFFPAGE TRUE
J 2
(-5475 1850);
DISPLAY 1.170213 (-5475 1850);
PAINT GREEN (-5475 1850);
DISPLAY INVISIBLE (-5475 1850);
FORCEPROP 1 LAST COMMENT_BODY TRUE
J 2
(-5275 1875);
DISPLAY 1.170213 (-5275 1875);
PAINT GREEN (-5275 1875);
DISPLAY INVISIBLE (-5275 1875);
FORCEADD OFFPAGE..1
(-4825 3450);
FORCEPROP 2 LAST $XR0 73 
J 0
(-5046 3450);
DISPLAY 0.638298 (-5046 3450);
PAINT MONO (-5046 3450);
FORCEPROP 2 LAST CDS_LIB mstr_standard
J 0
(-4825 3450);
PAINT MONO (-4825 3450);
DISPLAY INVISIBLE (-4825 3450);
FORCEPROP 2 LAST PATH I50
J 0
(-4775 3525);
DISPLAY 1.021277 (-4775 3525);
PAINT ORANGE (-4775 3525);
DISPLAY INVISIBLE (-4775 3525);
FORCEPROP 1 LAST OFFPAGE TRUE
J 0
(-4500 3325);
DISPLAY 1.170213 (-4500 3325);
PAINT GREEN (-4500 3325);
DISPLAY INVISIBLE (-4500 3325);
FORCEPROP 1 LAST COMMENT_BODY TRUE
J 0
(-4700 3350);
DISPLAY 1.170213 (-4700 3350);
PAINT GREEN (-4700 3350);
DISPLAY INVISIBLE (-4700 3350);
FORCEADD GND..1
(-2150 950);
FORCEPROP 3 LASTPIN (-2150 1000) SIG_NAME GND\g
J 0
(-2140 1010);
DISPLAY 0.659574 (-2140 1010);
PAINT MONO (-2140 1010);
DISPLAY INVISIBLE (-2140 1010);
FORCEPROP 1 LAST PATH I56
J 0
(-2075 950);
DISPLAY 0.872340 (-2075 950);
PAINT AQUA (-2075 950);
DISPLAY INVISIBLE (-2075 950);
FORCEPROP 1 LAST SIZE 1B
J 0
(-2075 900);
DISPLAY 1.404255 (-2075 900);
PAINT AQUA (-2075 900);
DISPLAY INVISIBLE (-2075 900);
FORCEPROP 2 LAST CDS_LIB mstr_symbols
J 0
(-2150 950);
PAINT MONO (-2150 950);
DISPLAY INVISIBLE (-2150 950);
FORCEPROP 1 LAST VOLTAGE 0.0V
J 0
(-2195 907);
DISPLAY 0.340426 (-2195 907);
PAINT SKYBLUE (-2195 907);
DISPLAY INVISIBLE (-2195 907);
FORCEPROP 1 LAST BODY_TYPE PLUMBING
J 0
(-2195 907);
DISPLAY 0.340426 (-2195 907);
PAINT GREEN (-2195 907);
DISPLAY INVISIBLE (-2195 907);
FORCEPROP 1 LAST HDL_POWER GND
J 0
(-2150 1100);
PAINT GREEN (-2150 1100);
DISPLAY INVISIBLE (-2150 1100);
FORCEADD GND..1
(-3975 925);
FORCEPROP 3 LASTPIN (-3975 975) SIG_NAME GND\g
J 0
(-3965 985);
DISPLAY 0.659574 (-3965 985);
PAINT MONO (-3965 985);
DISPLAY INVISIBLE (-3965 985);
FORCEPROP 1 LAST PATH I60
J 0
(-3900 925);
DISPLAY 0.872340 (-3900 925);
PAINT AQUA (-3900 925);
DISPLAY INVISIBLE (-3900 925);
FORCEPROP 2 LAST CDS_LIB mstr_symbols
J 0
(-3975 925);
PAINT MONO (-3975 925);
DISPLAY INVISIBLE (-3975 925);
FORCEPROP 1 LAST SIZE 1B
J 0
(-3900 875);
DISPLAY 1.404255 (-3900 875);
PAINT AQUA (-3900 875);
DISPLAY INVISIBLE (-3900 875);
FORCEPROP 1 LAST VOLTAGE 0.0V
J 0
(-4020 882);
DISPLAY 0.340426 (-4020 882);
PAINT SKYBLUE (-4020 882);
DISPLAY INVISIBLE (-4020 882);
FORCEPROP 1 LAST BODY_TYPE PLUMBING
J 0
(-4020 882);
DISPLAY 0.340426 (-4020 882);
PAINT GREEN (-4020 882);
DISPLAY INVISIBLE (-4020 882);
FORCEPROP 1 LAST HDL_POWER GND
J 0
(-3975 1075);
PAINT GREEN (-3975 1075);
DISPLAY INVISIBLE (-3975 1075);
FORCEADD CAPP..1
(-1900 3100);
FORCEPROP 1 LAST PART_NUMBER 699013-049
J 0
(-1850 2900);
DISPLAY 0.617021 (-1850 2900);
PAINT BLUE (-1850 2900);
FORCEPROP 1 LAST VALUE 470UF
J 0
(-1850 3150);
DISPLAY 0.617021 (-1850 3150);
PAINT SKYBLUE (-1850 3150);
FORCEPROP 1 LAST PACK_TYPE 3018
J 0
(-1850 2950);
DISPLAY 0.617021 (-1850 2950);
PAINT SKYBLUE (-1850 2950);
FORCEPROP 1 LASTPIN (-1900 3000) $PN 2
J 0
(-1890 2985);
DISPLAY 0.617021 (-1890 2985);
PAINT WHITE (-1890 2985);
FORCEPROP 1 LAST MATERIAL ALUM
J 0
(-1850 3000);
DISPLAY 0.617021 (-1850 3000);
PAINT SKYBLUE (-1850 3000);
FORCEPROP 1 LAST VOLTAGE 2.5V
J 0
(-1850 3050);
DISPLAY 0.659574 (-1850 3050);
PAINT SKYBLUE (-1850 3050);
FORCEPROP 1 LAST TOLERANCE 20%
J 0
(-1850 3100);
DISPLAY 0.617021 (-1850 3100);
PAINT SKYBLUE (-1850 3100);
FORCEPROP 1 LASTPIN (-1900 3200) $PN 1
J 0
(-1890 3185);
DISPLAY 0.617021 (-1890 3185);
PAINT WHITE (-1890 3185);
FORCEPROP 1 LAST LOCATION C4E24
J 0
(-1850 3200);
DISPLAY 0.617021 (-1850 3200);
PAINT AQUA (-1850 3200);
FORCEPROP 0 LAST GROUP PWR_MCP_CAP
J 0
(-1860 2851);
DISPLAY 0.638298 (-1860 2851);
PAINT BROWN (-1860 2851);
DISPLAY BOTH (-1860 2851);
FORCEPROP 2 LAST CDS_LIB mstr_discrete
J 0
(-1900 3100);
DISPLAY 1.617021 (-1900 3100);
PAINT ORANGE (-1900 3100);
DISPLAY INVISIBLE (-1900 3100);
FORCEPROP 2 LAST CDS_SEC 1
J 0
(-1850 3300);
DISPLAY 1.617021 (-1850 3300);
PAINT MONO (-1850 3300);
DISPLAY INVISIBLE (-1850 3300);
FORCEPROP 2 LAST CDS_LOCATION C4E24
J 0
(-1850 3200);
DISPLAY 0.617021 (-1850 3200);
PAINT AQUA (-1850 3200);
DISPLAY INVISIBLE (-1850 3200);
FORCEPROP 2 LAST $SEC 1
J 0
(-1850 3300);
DISPLAY 1.617021 (-1850 3300);
PAINT MONO (-1850 3300);
DISPLAY INVISIBLE (-1850 3300);
FORCEPROP 1 LAST PATH I61
J 0
(-1850 3250);
DISPLAY 0.978723 (-1850 3250);
PAINT ORANGE (-1850 3250);
DISPLAY INVISIBLE (-1850 3250);
FORCEPROP 2 LAST BOM_COST PVMCP_MCP_CPU1_VR
J 0
(-1850 3250);
DISPLAY 1.617021 (-1850 3250);
PAINT WHITE (-1850 3250);
DISPLAY INVISIBLE (-1850 3250);
FORCEPROP 2 LAST ROOM PVMCP_MCP_CPU1_VR
J 0
(-1850 3225);
DISPLAY 1.617021 (-1850 3225);
PAINT WHITE (-1850 3225);
DISPLAY INVISIBLE (-1850 3225);
FORCEADD CAPP..1
(-1600 3100);
FORCEPROP 1 LAST VOLTAGE 2.5V
J 0
(-1550 3050);
DISPLAY 0.659574 (-1550 3050);
PAINT SKYBLUE (-1550 3050);
FORCEPROP 1 LAST TOLERANCE 20%
J 0
(-1550 3100);
DISPLAY 0.617021 (-1550 3100);
PAINT SKYBLUE (-1550 3100);
FORCEPROP 1 LASTPIN (-1600 3200) $PN 1
J 0
(-1590 3185);
DISPLAY 0.617021 (-1590 3185);
PAINT WHITE (-1590 3185);
FORCEPROP 1 LASTPIN (-1600 3000) $PN 2
J 0
(-1590 2985);
DISPLAY 0.617021 (-1590 2985);
PAINT WHITE (-1590 2985);
FORCEPROP 1 LAST VALUE 470UF
J 0
(-1550 3150);
DISPLAY 0.617021 (-1550 3150);
PAINT SKYBLUE (-1550 3150);
FORCEPROP 1 LAST LOCATION C6R16
J 0
(-1550 3200);
DISPLAY 0.617021 (-1550 3200);
PAINT AQUA (-1550 3200);
FORCEPROP 1 LAST MATERIAL ALUM
J 0
(-1550 3000);
DISPLAY 0.617021 (-1550 3000);
PAINT SKYBLUE (-1550 3000);
FORCEPROP 1 LAST PACK_TYPE 3018
J 0
(-1550 2950);
DISPLAY 0.617021 (-1550 2950);
PAINT SKYBLUE (-1550 2950);
FORCEPROP 1 LAST PART_NUMBER 699013-049
J 0
(-1550 2900);
DISPLAY 0.617021 (-1550 2900);
PAINT BLUE (-1550 2900);
FORCEPROP 0 LAST GROUP PWR_MCP_CAP
J 0
(-1560 2801);
DISPLAY 0.638298 (-1560 2801);
PAINT BROWN (-1560 2801);
DISPLAY BOTH (-1560 2801);
FORCEPROP 2 LAST ROOM PVMCP_MCP_CPU1_VR
J 0
(-1550 3225);
DISPLAY 1.617021 (-1550 3225);
PAINT WHITE (-1550 3225);
DISPLAY INVISIBLE (-1550 3225);
FORCEPROP 1 LAST PATH I62
J 0
(-1550 3250);
DISPLAY 0.978723 (-1550 3250);
PAINT ORANGE (-1550 3250);
DISPLAY INVISIBLE (-1550 3250);
FORCEPROP 2 LAST CDS_LOCATION C6R16
J 0
(-1550 3200);
DISPLAY 0.617021 (-1550 3200);
PAINT AQUA (-1550 3200);
DISPLAY INVISIBLE (-1550 3200);
FORCEPROP 2 LAST SEC 1
J 0
(-1545 3320);
DISPLAY 1.106383 (-1545 3320);
PAINT MONO (-1545 3320);
DISPLAY INVISIBLE (-1545 3320);
FORCEPROP 2 LAST CDS_LIB mstr_discrete
J 0
(-1600 3100);
DISPLAY 1.617021 (-1600 3100);
PAINT ORANGE (-1600 3100);
DISPLAY INVISIBLE (-1600 3100);
FORCEPROP 2 LAST BOM_COST PVMCP_MCP_CPU1_VR
J 0
(-1550 3250);
DISPLAY 1.617021 (-1550 3250);
PAINT WHITE (-1550 3250);
DISPLAY INVISIBLE (-1550 3250);
FORCEPROP 2 LAST SEC_TYPE 3018
J 0
(-1545 3320);
DISPLAY 1.659574 (-1545 3320);
PAINT ORANGE (-1545 3320);
DISPLAY INVISIBLE (-1545 3320);
FORCEADD GND..1
(-1900 2175);
FORCEPROP 3 LASTPIN (-1900 2225) SIG_NAME GND\g
J 0
(-1890 2235);
DISPLAY 0.659574 (-1890 2235);
PAINT MONO (-1890 2235);
DISPLAY INVISIBLE (-1890 2235);
FORCEPROP 1 LAST HDL_POWER GND
J 0
(-1900 2325);
DISPLAY 1.191489 (-1900 2325);
PAINT GREEN (-1900 2325);
DISPLAY INVISIBLE (-1900 2325);
FORCEPROP 1 LAST BODY_TYPE PLUMBING
J 0
(-1945 2132);
DISPLAY 0.340426 (-1945 2132);
PAINT GREEN (-1945 2132);
DISPLAY INVISIBLE (-1945 2132);
FORCEPROP 1 LAST VOLTAGE 0
J 0
(-1900 2175);
DISPLAY 1.340426 (-1900 2175);
PAINT SKYBLUE (-1900 2175);
DISPLAY INVISIBLE (-1900 2175);
FORCEPROP 2 LAST CDS_LIB mstr_symbols
J 0
(-1900 2175);
PAINT MONO (-1900 2175);
DISPLAY INVISIBLE (-1900 2175);
FORCEPROP 1 LAST SIZE 1B
J 0
(-1825 2125);
DISPLAY 1.191489 (-1825 2125);
PAINT GREEN (-1825 2125);
DISPLAY INVISIBLE (-1825 2125);
FORCEPROP 1 LAST PATH I64
J 0
(-1825 2175);
DISPLAY 0.872340 (-1825 2175);
PAINT AQUA (-1825 2175);
DISPLAY INVISIBLE (-1825 2175);
FORCEADD CAP_A..1
(-1000 2450);
FORCEPROP 1 LAST MATERIAL X6S
J 0
(-950 2350);
DISPLAY 0.617021 (-950 2350);
PAINT SKYBLUE (-950 2350);
FORCEPROP 1 LAST PART_NUMBER D97712-004
J 0
(-950 2300);
DISPLAY 0.617021 (-950 2300);
PAINT BLUE (-950 2300);
FORCEPROP 1 LAST PACK_TYPE 0402V
J 0
(-950 2250);
DISPLAY 0.617021 (-950 2250);
PAINT SKYBLUE (-950 2250);
FORCEPROP 1 LAST LOCATION C4F1
J 0
(-950 2550);
DISPLAY 0.617021 (-950 2550);
PAINT AQUA (-950 2550);
FORCEPROP 1 LASTPIN (-1000 2350) $PN 2
J 0
(-990 2330);
DISPLAY 0.617021 (-990 2330);
PAINT ORANGE (-990 2330);
FORCEPROP 1 LASTPIN (-1000 2550) $PN 1
J 0
(-990 2530);
DISPLAY 0.617021 (-990 2530);
PAINT ORANGE (-990 2530);
FORCEPROP 1 LAST VALUE 1.0UF
J 0
(-950 2500);
DISPLAY 0.617021 (-950 2500);
PAINT SKYBLUE (-950 2500);
FORCEPROP 0 LAST GROUP PWR_MCP_CAP
J 0
(-960 2151);
DISPLAY 0.638298 (-960 2151);
PAINT BROWN (-960 2151);
DISPLAY BOTH (-960 2151);
FORCEPROP 1 LAST TOLERANCE 10%
J 0
(-950 2400);
DISPLAY 0.617021 (-950 2400);
PAINT SKYBLUE (-950 2400);
FORCEPROP 1 LAST VOLTAGE 6.3V
J 0
(-950 2450);
DISPLAY 0.617021 (-950 2450);
PAINT SKYBLUE (-950 2450);
FORCEPROP 2 LAST CDS_LOCATION C4F1
J 0
(-950 2550);
DISPLAY 0.617021 (-950 2550);
PAINT AQUA (-950 2550);
DISPLAY INVISIBLE (-950 2550);
FORCEPROP 2 LAST CDS_LIB dev_discrete
J 2
(-1000 2450);
PAINT ORANGE (-1000 2450);
DISPLAY INVISIBLE (-1000 2450);
FORCEPROP 2 LAST CDS_SEC 1
J 2
(-950 2600);
PAINT ORANGE (-950 2600);
DISPLAY INVISIBLE (-950 2600);
FORCEPROP 2 LAST SEC_TYPE 0402V
J 2
(-950 2650);
DISPLAY 1.021277 (-950 2650);
PAINT ORANGE (-950 2650);
DISPLAY INVISIBLE (-950 2650);
FORCEPROP 2 LAST SEC 1
J 2
(-950 2650);
DISPLAY 0.680851 (-950 2650);
PAINT MONO (-950 2650);
DISPLAY INVISIBLE (-950 2650);
FORCEPROP 1 LAST PATH I68
J 0
(-950 2600);
DISPLAY 0.978723 (-950 2600);
PAINT WHITE (-950 2600);
DISPLAY INVISIBLE (-950 2600);
FORCEPROP 2 LAST ROOM P1V8_MCP_CPU1
J 0
(-950 2600);
DISPLAY 1.659574 (-950 2600);
PAINT WHITE (-950 2600);
DISPLAY INVISIBLE (-950 2600);
FORCEADD CAP_A..1
(-1300 2450);
FORCEPROP 1 LAST LOCATION C4F3
J 0
(-1250 2550);
DISPLAY 0.617021 (-1250 2550);
PAINT AQUA (-1250 2550);
FORCEPROP 1 LASTPIN (-1300 2350) $PN 2
J 0
(-1290 2330);
DISPLAY 0.617021 (-1290 2330);
PAINT ORANGE (-1290 2330);
FORCEPROP 1 LASTPIN (-1300 2550) $PN 1
J 0
(-1290 2530);
DISPLAY 0.617021 (-1290 2530);
PAINT ORANGE (-1290 2530);
FORCEPROP 1 LAST VOLTAGE 6.3V
J 0
(-1250 2450);
DISPLAY 0.617021 (-1250 2450);
PAINT SKYBLUE (-1250 2450);
FORCEPROP 1 LAST VALUE 1.0UF
J 0
(-1250 2500);
DISPLAY 0.617021 (-1250 2500);
PAINT SKYBLUE (-1250 2500);
FORCEPROP 1 LAST TOLERANCE 10%
J 0
(-1250 2400);
DISPLAY 0.617021 (-1250 2400);
PAINT SKYBLUE (-1250 2400);
FORCEPROP 1 LAST MATERIAL X6S
J 0
(-1250 2350);
DISPLAY 0.617021 (-1250 2350);
PAINT SKYBLUE (-1250 2350);
FORCEPROP 1 LAST PACK_TYPE 0402V
J 0
(-1250 2250);
DISPLAY 0.617021 (-1250 2250);
PAINT SKYBLUE (-1250 2250);
FORCEPROP 1 LAST PART_NUMBER D97712-004
J 0
(-1250 2300);
DISPLAY 0.617021 (-1250 2300);
PAINT BLUE (-1250 2300);
FORCEPROP 0 LAST GROUP PWR_MCP_CAP
J 0
(-1260 2201);
DISPLAY 0.638298 (-1260 2201);
PAINT BROWN (-1260 2201);
DISPLAY BOTH (-1260 2201);
FORCEPROP 2 LAST ROOM P1V8_MCP_CPU1
J 0
(-1250 2600);
DISPLAY 1.659574 (-1250 2600);
PAINT WHITE (-1250 2600);
DISPLAY INVISIBLE (-1250 2600);
FORCEPROP 1 LAST PATH I70
J 0
(-1250 2600);
DISPLAY 0.978723 (-1250 2600);
PAINT WHITE (-1250 2600);
DISPLAY INVISIBLE (-1250 2600);
FORCEPROP 2 LAST SEC 1
J 2
(-1250 2650);
DISPLAY 0.680851 (-1250 2650);
PAINT MONO (-1250 2650);
DISPLAY INVISIBLE (-1250 2650);
FORCEPROP 2 LAST SEC_TYPE 0402V
J 2
(-1250 2650);
DISPLAY 1.021277 (-1250 2650);
PAINT ORANGE (-1250 2650);
DISPLAY INVISIBLE (-1250 2650);
FORCEPROP 2 LAST CDS_SEC 1
J 2
(-1250 2600);
PAINT ORANGE (-1250 2600);
DISPLAY INVISIBLE (-1250 2600);
FORCEPROP 2 LAST CDS_LIB dev_discrete
J 2
(-1300 2450);
PAINT ORANGE (-1300 2450);
DISPLAY INVISIBLE (-1300 2450);
FORCEPROP 2 LAST CDS_LOCATION C4F3
J 0
(-1250 2550);
DISPLAY 0.617021 (-1250 2550);
PAINT AQUA (-1250 2550);
DISPLAY INVISIBLE (-1250 2550);
FORCEADD GND..1
(-1300 2175);
FORCEPROP 3 LASTPIN (-1300 2225) SIG_NAME GND\g
J 0
(-1290 2235);
DISPLAY 0.659574 (-1290 2235);
PAINT MONO (-1290 2235);
DISPLAY INVISIBLE (-1290 2235);
FORCEPROP 1 LAST HDL_POWER GND
J 0
(-1300 2325);
PAINT GREEN (-1300 2325);
DISPLAY INVISIBLE (-1300 2325);
FORCEPROP 1 LAST BODY_TYPE PLUMBING
J 0
(-1345 2132);
DISPLAY 0.340426 (-1345 2132);
PAINT GREEN (-1345 2132);
DISPLAY INVISIBLE (-1345 2132);
FORCEPROP 1 LAST PATH I75
J 0
(-1225 2175);
DISPLAY 0.872340 (-1225 2175);
PAINT AQUA (-1225 2175);
DISPLAY INVISIBLE (-1225 2175);
FORCEPROP 2 LAST CDS_LIB mstr_symbols
J 0
(-1300 2175);
PAINT ORANGE (-1300 2175);
DISPLAY INVISIBLE (-1300 2175);
FORCEPROP 1 LAST SIZE 1B
J 0
(-1225 2125);
DISPLAY 1.404255 (-1225 2125);
PAINT AQUA (-1225 2125);
DISPLAY INVISIBLE (-1225 2125);
FORCEPROP 1 LAST VOLTAGE 0.0V
J 0
(-1345 2132);
DISPLAY 0.340426 (-1345 2132);
PAINT SKYBLUE (-1345 2132);
DISPLAY INVISIBLE (-1345 2132);
FORCEADD GND..1
(-1900 2825);
FORCEPROP 3 LASTPIN (-1900 2875) SIG_NAME GND\g
J 0
(-1890 2885);
DISPLAY 0.659574 (-1890 2885);
PAINT MONO (-1890 2885);
DISPLAY INVISIBLE (-1890 2885);
FORCEPROP 2 LAST ROOM PVSA_CPU0_DECAP_VR
J 0
(-2450 2900);
DISPLAY 1.936170 (-2450 2900);
PAINT ORANGE (-2450 2900);
DISPLAY INVISIBLE (-2450 2900);
FORCEPROP 1 LAST PATH I81
J 0
(-1825 2825);
DISPLAY 0.872340 (-1825 2825);
PAINT AQUA (-1825 2825);
DISPLAY INVISIBLE (-1825 2825);
FORCEPROP 2 LAST CDS_LIB mstr_symbols
J 0
(-1900 2825);
PAINT MONO (-1900 2825);
DISPLAY INVISIBLE (-1900 2825);
FORCEPROP 1 LAST SIZE 1B
J 0
(-1825 2775);
DISPLAY 1.723404 (-1825 2775);
PAINT GREEN (-1825 2775);
DISPLAY INVISIBLE (-1825 2775);
FORCEPROP 2 LAST BOM_COST PROC_VRD_VCCIN_CPU0
J 0
(-2275 2900);
DISPLAY 1.446809 (-2275 2900);
PAINT MONO (-2275 2900);
DISPLAY INVISIBLE (-2275 2900);
FORCEPROP 1 LAST VOLTAGE 0
J 0
(-1900 2825);
PAINT SKYBLUE (-1900 2825);
DISPLAY INVISIBLE (-1900 2825);
FORCEPROP 1 LAST BODY_TYPE PLUMBING
J 0
(-1945 2782);
DISPLAY 0.340426 (-1945 2782);
PAINT GREEN (-1945 2782);
DISPLAY INVISIBLE (-1945 2782);
FORCEPROP 1 LAST HDL_POWER GND
J 0
(-1900 2975);
DISPLAY 1.723404 (-1900 2975);
PAINT GREEN (-1900 2975);
DISPLAY INVISIBLE (-1900 2975);
FORCEADD OFFPAGE..1
(-7675 1775);
FORCEPROP 2 LAST $XR0 73 
J 0
(-7896 1775);
DISPLAY 0.638298 (-7896 1775);
PAINT MONO (-7896 1775);
FORCEPROP 2 LAST PATH I83
J 0
(-7500 1850);
DISPLAY 1.021277 (-7500 1850);
PAINT ORANGE (-7500 1850);
DISPLAY INVISIBLE (-7500 1850);
FORCEPROP 2 LAST BOM_COST PROC_VRD_VCCIN_CPU0
J 0
(-7350 1825);
PAINT MONO (-7350 1825);
DISPLAY INVISIBLE (-7350 1825);
FORCEPROP 2 LAST CDS_LIB mstr_standard
J 0
(-7675 1775);
PAINT MONO (-7675 1775);
DISPLAY INVISIBLE (-7675 1775);
FORCEPROP 2 LAST ROOM PVSA_CPU0_VSENSE_VR
J 0
(-8075 1850);
PAINT ORANGE (-8075 1850);
DISPLAY INVISIBLE (-8075 1850);
FORCEPROP 1 LAST OFFPAGE TRUE
J 0
(-7350 1650);
DISPLAY 0.872340 (-7350 1650);
PAINT GREEN (-7350 1650);
DISPLAY INVISIBLE (-7350 1650);
FORCEPROP 1 LAST COMMENT_BODY TRUE
J 0
(-7550 1675);
DISPLAY 0.872340 (-7550 1675);
PAINT GREEN (-7550 1675);
DISPLAY INVISIBLE (-7550 1675);
FORCEADD OFFPAGE..1
(-7675 1725);
FORCEPROP 2 LAST $XR0 73 
J 0
(-7896 1725);
DISPLAY 0.638298 (-7896 1725);
PAINT MONO (-7896 1725);
FORCEPROP 2 LAST PATH I84
J 0
(-7625 1800);
DISPLAY 1.021277 (-7625 1800);
PAINT ORANGE (-7625 1800);
DISPLAY INVISIBLE (-7625 1800);
FORCEPROP 2 LAST CDS_LIB mstr_standard
J 0
(-7675 1725);
PAINT MONO (-7675 1725);
DISPLAY INVISIBLE (-7675 1725);
FORCEPROP 2 LAST ROOM PVSA_CPU0_VSENSE_VR
J 0
(-8075 1800);
PAINT ORANGE (-8075 1800);
DISPLAY INVISIBLE (-8075 1800);
FORCEPROP 2 LAST BOM_COST PROC_VRD_VCCIN_CPU0
J 0
(-7350 1775);
PAINT MONO (-7350 1775);
DISPLAY INVISIBLE (-7350 1775);
FORCEPROP 1 LAST OFFPAGE TRUE
J 0
(-7350 1600);
DISPLAY 0.872340 (-7350 1600);
PAINT GREEN (-7350 1600);
DISPLAY INVISIBLE (-7350 1600);
FORCEPROP 1 LAST COMMENT_BODY TRUE
J 0
(-7550 1625);
DISPLAY 0.872340 (-7550 1625);
PAINT GREEN (-7550 1625);
DISPLAY INVISIBLE (-7550 1625);
FORCEADD GND..1
(-7150 1875);
FORCEPROP 3 LASTPIN (-7150 1925) SIG_NAME GND\g
J 0
(-7140 1935);
DISPLAY 0.659574 (-7140 1935);
PAINT MONO (-7140 1935);
DISPLAY INVISIBLE (-7140 1935);
FORCEPROP 1 LAST PATH I85
J 0
(-7075 1875);
DISPLAY 0.872340 (-7075 1875);
PAINT AQUA (-7075 1875);
DISPLAY INVISIBLE (-7075 1875);
FORCEPROP 1 LAST SIZE 1B
J 0
(-7075 1825);
DISPLAY 1.404255 (-7075 1825);
PAINT AQUA (-7075 1825);
DISPLAY INVISIBLE (-7075 1825);
FORCEPROP 2 LAST CDS_LIB mstr_symbols
J 0
(-7150 1875);
PAINT MONO (-7150 1875);
DISPLAY INVISIBLE (-7150 1875);
FORCEPROP 1 LAST VOLTAGE 0.0V
J 0
(-7195 1832);
DISPLAY 0.340426 (-7195 1832);
PAINT SKYBLUE (-7195 1832);
DISPLAY INVISIBLE (-7195 1832);
FORCEPROP 1 LAST BODY_TYPE PLUMBING
J 0
(-7195 1832);
DISPLAY 0.340426 (-7195 1832);
PAINT GREEN (-7195 1832);
DISPLAY INVISIBLE (-7195 1832);
FORCEPROP 1 LAST HDL_POWER GND
J 0
(-7150 2025);
PAINT GREEN (-7150 2025);
DISPLAY INVISIBLE (-7150 2025);
FORCEADD P12V_STBY..1
(-6950 4750);
FORCEPROP 3 LASTPIN (-6950 4700) SIG_NAME P12V_STBY\g
J 0
(-6940 4710);
DISPLAY 0.659574 (-6940 4710);
PAINT MONO (-6940 4710);
DISPLAY INVISIBLE (-6940 4710);
FORCEPROP 1 LAST PATH I86
J 0
(-6905 4752);
DISPLAY 0.340426 (-6905 4752);
PAINT GREEN (-6905 4752);
DISPLAY INVISIBLE (-6905 4752);
FORCEPROP 1 LAST SIZE 1B
J 0
(-6905 4772);
DISPLAY 0.340426 (-6905 4772);
PAINT GREEN (-6905 4772);
DISPLAY INVISIBLE (-6905 4772);
FORCEPROP 2 LAST CDS_LIB mstr_symbols
J 0
(-6950 4750);
PAINT MONO (-6950 4750);
DISPLAY INVISIBLE (-6950 4750);
FORCEPROP 1 LAST VOLTAGE 12.0V
J 0
(-6995 4707);
DISPLAY 0.340426 (-6995 4707);
PAINT SKYBLUE (-6995 4707);
DISPLAY INVISIBLE (-6995 4707);
FORCEPROP 1 LAST BODY_TYPE PLUMBING
J 0
(-6995 4707);
DISPLAY 0.340426 (-6995 4707);
PAINT GREEN (-6995 4707);
DISPLAY INVISIBLE (-6995 4707);
FORCEPROP 1 LAST HDL_POWER P12V_STBY
J 0
(-7250 4625);
DISPLAY 0.872340 (-7250 4625);
PAINT ORANGE (-7250 4625);
DISPLAY INVISIBLE (-7250 4625);
FORCEADD P3V3_STBY..1
(-5525 4525);
FORCEPROP 3 LASTPIN (-5525 4475) SIG_NAME P3V3_STBY\g
J 0
(-5515 4485);
DISPLAY 0.659574 (-5515 4485);
PAINT MONO (-5515 4485);
DISPLAY INVISIBLE (-5515 4485);
FORCEPROP 1 LAST PATH I87
J 0
(-5480 4527);
DISPLAY 0.340426 (-5480 4527);
PAINT GREEN (-5480 4527);
DISPLAY INVISIBLE (-5480 4527);
FORCEPROP 1 LAST SIZE 1B
J 0
(-5480 4547);
DISPLAY 0.340426 (-5480 4547);
PAINT GREEN (-5480 4547);
DISPLAY INVISIBLE (-5480 4547);
FORCEPROP 2 LAST CDS_LIB mstr_symbols
J 0
(-5525 4525);
PAINT MONO (-5525 4525);
DISPLAY INVISIBLE (-5525 4525);
FORCEPROP 1 LAST VOLTAGE +3.3V
J 0
(-5325 4675);
DISPLAY 1.021277 (-5325 4675);
PAINT SKYBLUE (-5325 4675);
DISPLAY INVISIBLE (-5325 4675);
FORCEPROP 1 LAST BODY_TYPE PLUMBING
J 0
(-5570 4482);
DISPLAY 0.340426 (-5570 4482);
PAINT GREEN (-5570 4482);
DISPLAY INVISIBLE (-5570 4482);
FORCEPROP 1 LAST HDL_POWER P3V3_STBY
J 0
(-5825 4400);
DISPLAY 0.872340 (-5825 4400);
PAINT ORANGE (-5825 4400);
DISPLAY INVISIBLE (-5825 4400);
FORCEADD P5V_STBY..1
(-5500 3850);
FORCEPROP 3 LASTPIN (-5500 3800) SIG_NAME P5V_STBY\g
J 0
(-5490 3810);
DISPLAY 0.659574 (-5490 3810);
PAINT MONO (-5490 3810);
DISPLAY INVISIBLE (-5490 3810);
FORCEPROP 1 LAST PATH I88
J 0
(-5455 3852);
DISPLAY 0.340426 (-5455 3852);
PAINT GREEN (-5455 3852);
DISPLAY INVISIBLE (-5455 3852);
FORCEPROP 1 LAST SIZE 1B
J 0
(-5455 3872);
DISPLAY 0.340426 (-5455 3872);
PAINT GREEN (-5455 3872);
DISPLAY INVISIBLE (-5455 3872);
FORCEPROP 2 LAST CDS_LIB mstr_symbols
J 0
(-5500 3850);
PAINT MONO (-5500 3850);
DISPLAY INVISIBLE (-5500 3850);
FORCEPROP 1 LAST VOLTAGE +5.0V
J 0
(-5300 4000);
DISPLAY 1.021277 (-5300 4000);
PAINT SKYBLUE (-5300 4000);
DISPLAY INVISIBLE (-5300 4000);
FORCEPROP 1 LAST BODY_TYPE PLUMBING
J 0
(-5545 3807);
DISPLAY 0.340426 (-5545 3807);
PAINT GREEN (-5545 3807);
DISPLAY INVISIBLE (-5545 3807);
FORCEPROP 1 LAST HDL_POWER P5V_STBY
J 0
(-5800 3725);
DISPLAY 0.872340 (-5800 3725);
PAINT ORANGE (-5800 3725);
DISPLAY INVISIBLE (-5800 3725);
FORCEADD OFFPAGE..4
(-5100 1275);
FORCEPROP 2 LAST $XR2 213 
J 0
(-4704 1275);
DISPLAY 0.638298 (-4704 1275);
PAINT MONO (-4704 1275);
FORCEPROP 2 LAST $XR1 206 
J 0
(-4824 1275);
DISPLAY 0.638298 (-4824 1275);
PAINT MONO (-4824 1275);
FORCEPROP 2 LAST $XR0 55 
J 0
(-4914 1275);
DISPLAY 0.638298 (-4914 1275);
PAINT MONO (-4914 1275);
FORCEPROP 2 LAST PATH I90
J 0
(-5050 1350);
DISPLAY 1.021277 (-5050 1350);
PAINT ORANGE (-5050 1350);
DISPLAY INVISIBLE (-5050 1350);
FORCEPROP 2 LAST ROOM P0V95_FPGA_CPU0_VR
J 0
(-5650 1350);
DISPLAY 1.361702 (-5650 1350);
PAINT ORANGE (-5650 1350);
DISPLAY INVISIBLE (-5650 1350);
FORCEPROP 2 LAST CDS_LIB mstr_standard
J 0
(-5100 1275);
PAINT MONO (-5100 1275);
DISPLAY INVISIBLE (-5100 1275);
FORCEPROP 1 LAST OFFPAGE TRUE
J 0
(-4775 1150);
DISPLAY 0.872340 (-4775 1150);
PAINT GREEN (-4775 1150);
DISPLAY INVISIBLE (-4775 1150);
FORCEPROP 1 LAST COMMENT_BODY TRUE
J 0
(-5125 1175);
DISPLAY 0.872340 (-5125 1175);
PAINT GREEN (-5125 1175);
DISPLAY INVISIBLE (-5125 1175);
FORCEADD GND..1
(-5125 2175);
FORCEPROP 3 LASTPIN (-5125 2225) SIG_NAME GND\g
J 0
(-5115 2235);
DISPLAY 0.659574 (-5115 2235);
PAINT MONO (-5115 2235);
DISPLAY INVISIBLE (-5115 2235);
FORCEPROP 1 LAST PATH I94
J 0
(-5050 2175);
DISPLAY 0.872340 (-5050 2175);
PAINT AQUA (-5050 2175);
DISPLAY INVISIBLE (-5050 2175);
FORCEPROP 1 LAST SIZE 1B
J 0
(-5050 2125);
DISPLAY 1.404255 (-5050 2125);
PAINT AQUA (-5050 2125);
DISPLAY INVISIBLE (-5050 2125);
FORCEPROP 2 LAST CDS_LIB mstr_symbols
J 0
(-5125 2175);
PAINT MONO (-5125 2175);
DISPLAY INVISIBLE (-5125 2175);
FORCEPROP 1 LAST VOLTAGE 0.0V
J 0
(-5170 2132);
DISPLAY 0.340426 (-5170 2132);
PAINT SKYBLUE (-5170 2132);
DISPLAY INVISIBLE (-5170 2132);
FORCEPROP 1 LAST BODY_TYPE PLUMBING
J 0
(-5170 2132);
DISPLAY 0.340426 (-5170 2132);
PAINT GREEN (-5170 2132);
DISPLAY INVISIBLE (-5170 2132);
FORCEPROP 1 LAST HDL_POWER GND
J 0
(-5125 2325);
PAINT GREEN (-5125 2325);
DISPLAY INVISIBLE (-5125 2325);
FORCEADD GND..1
(-7125 1425);
FORCEPROP 3 LASTPIN (-7125 1475) SIG_NAME GND\g
J 0
(-7115 1485);
DISPLAY 0.659574 (-7115 1485);
PAINT MONO (-7115 1485);
DISPLAY INVISIBLE (-7115 1485);
FORCEPROP 1 LAST PATH I95
J 0
(-7050 1425);
DISPLAY 0.872340 (-7050 1425);
PAINT AQUA (-7050 1425);
DISPLAY INVISIBLE (-7050 1425);
FORCEPROP 1 LAST SIZE 1B
J 0
(-7050 1375);
DISPLAY 1.404255 (-7050 1375);
PAINT AQUA (-7050 1375);
DISPLAY INVISIBLE (-7050 1375);
FORCEPROP 2 LAST CDS_LIB mstr_symbols
J 0
(-7125 1425);
PAINT MONO (-7125 1425);
DISPLAY INVISIBLE (-7125 1425);
FORCEPROP 1 LAST VOLTAGE 0.0V
J 0
(-7170 1382);
DISPLAY 0.340426 (-7170 1382);
PAINT SKYBLUE (-7170 1382);
DISPLAY INVISIBLE (-7170 1382);
FORCEPROP 1 LAST BODY_TYPE PLUMBING
J 0
(-7170 1382);
DISPLAY 0.340426 (-7170 1382);
PAINT GREEN (-7170 1382);
DISPLAY INVISIBLE (-7170 1382);
FORCEPROP 1 LAST HDL_POWER GND
J 0
(-7125 1575);
PAINT GREEN (-7125 1575);
DISPLAY INVISIBLE (-7125 1575);
FORCEADD DESIGN_NOTE..1
(-6850 700);
PAINT PURPLE (-6850 700);
FORCEPROP 0 LAST L1 SMBUS ADDRESS
J 0
(-7050 575);
PAINT VIOLET (-7050 575);
FORCEPROP 0 LAST L4 SVID ADDRESS
J 0
(-7050 350);
DISPLAY 1.021277 (-7050 350);
PAINT VIOLET (-7050 350);
FORCEPROP 0 LAST L2 PVCCMCP_CPU1: 0XB8
J 0
(-7050 500);
DISPLAY 1.021277 (-7050 500);
PAINT VIOLET (-7050 500);
FORCEPROP 0 LAST L7 P1V8_MCP_CPU1: 0X05(BUS #2)
J 0
(-7050 125);
DISPLAY 1.021277 (-7050 125);
PAINT VIOLET (-7050 125);
FORCEPROP 0 LAST L6 PVCCIOMCP_CPU1:0X04(BUS #2)
J 0
(-7050 200);
DISPLAY 1.021277 (-7050 200);
PAINT VIOLET (-7050 200);
FORCEPROP 0 LAST L5 PVCCMCP_CPU1: 0X03(BUS #1)
J 0
(-7050 275);
DISPLAY 1.021277 (-7050 275);
PAINT VIOLET (-7050 275);
FORCEPROP 0 LAST L3 PVCCIOMCP_CPU1 & P1V8_MCP_CPU1: 0XC8
J 0
(-7050 425);
DISPLAY 1.021277 (-7050 425);
PAINT VIOLET (-7050 425);
FORCEPROP 2 LAST ROOM PVCCIN_CPU0_VR
J 0
(-7050 650);
PAINT MONO (-7050 650);
DISPLAY INVISIBLE (-7050 650);
FORCEPROP 2 LAST CDS_LIB mstr_symbols
J 0
(-6850 700);
PAINT MONO (-6850 700);
DISPLAY INVISIBLE (-6850 700);
FORCEPROP 2 LAST BOM_COST SM_CONTROLLER
J 0
(-7050 650);
PAINT MONO (-7050 650);
DISPLAY INVISIBLE (-7050 650);
FORCEPROP 1 LAST COMMENT_BODY TRUE
J 0
(-6825 800);
DISPLAY 1.319149 (-6825 800);
PAINT GREEN (-6825 800);
DISPLAY INVISIBLE (-6825 800);
FORCEADD INTEL_CORP_BPAGE..1
(-275 50);
FORCEPROP 1 LAST CDS_CON_LAST_MODIFIED Fri Jun 16 17:49:11 2017
J 0
(-1700 375);
DISPLAY 1.361702 (-1700 375);
PAINT GREEN (-1700 375);
DISPLAY INVISIBLE (-1700 375);
FORCEPROP 1 LAST CUSTOM_TXT_CDS <CURRENT_DESIGN_SHEET> OF <TOTAL_DESIGN_SHEETS>
J 0
(-775 75);
PAINT ORANGE (-775 75);
FORCEPROP 1 LAST CUSTOM_TXT_CDS <CON_LAST_MODIFIED>
J 0
(-4275 150);
PAINT ORANGE (-4275 150);
FORCEPROP 2 LAST CUSTOM_TXT_CDS <XR_PAGE_TITLE>
J 0
(-8165 5300);
DISPLAY 0.638298 (-8165 5300);
PAINT PINK (-8165 5300);
DISPLAY INVISIBLE (-8165 5300);
FORCEPROP 1 LAST SCH_TITLE MCP CPU1 VRM
J 0
(-8200 100);
DISPLAY 1.212766 (-8200 100);
PAINT ORANGE (-8200 100);
FORCEPROP 2 LAST CDS_LIB mstr_symbols
J 0
(-275 50);
DISPLAY 1.361702 (-275 50);
PAINT ORANGE (-275 50);
DISPLAY INVISIBLE (-275 50);
FORCEPROP 2 LAST PAGE_BORDER TRUE
J 0
(-8165 5300);
DISPLAY 0.851064 (-8165 5300);
PAINT PINK (-8165 5300);
DISPLAY INVISIBLE (-8165 5300);
FORCEPROP 1 LAST COMMENT_BODY TRUE
J 0
(-263 62);
DISPLAY 0.617021 (-263 62);
PAINT GREEN (-263 62);
DISPLAY INVISIBLE (-263 62);
FORCEPROP 2 LAST CDS_XR_PAGE_TITLE CR-193 : @BASEBOARD_FAB2_LIB.BASEBOARD_FAB2(SCH_1):PAGE193
J 0
(-8165 5300);
DISPLAY 0.638298 (-8165 5300);
PAINT PINK (-8165 5300);
DISPLAY INVISIBLE (-8165 5300);
WIRE 16 -1 (-3800 4500)(-3800 4650);
WIRE 16 -1 (-3725 4500)(-3800 4500);
WIRE 16 -1 (-3725 4450)(-3725 4500);
WIRE 16 -1 (-3550 4500)(-3725 4500);
WIRE 16 -1 (-3725 4400)(-3725 4450);
WIRE 16 -1 (-3550 4450)(-3725 4450);
WIRE 16 -1 (-3725 4150)(-3725 4400);
WIRE 16 -1 (-3550 4400)(-3725 4400);
WIRE 16 -1 (-3725 4100)(-3725 4150);
WIRE 16 -1 (-3550 4150)(-3725 4150);
WIRE 16 -1 (-3725 4050)(-3725 4100);
WIRE 16 -1 (-3550 4100)(-3725 4100);
WIRE 16 -1 (-3725 3800)(-3725 4050);
WIRE 16 -1 (-3550 4050)(-3725 4050);
WIRE 16 -1 (-3725 3750)(-3725 3800);
WIRE 16 -1 (-3550 3800)(-3725 3800);
WIRE 16 -1 (-3725 3700)(-3725 3750);
WIRE 16 -1 (-3550 3750)(-3725 3750);
WIRE 16 -1 (-3550 3700)(-3725 3700);
WIRE 16 -1 (-4050 4600)(-4050 4525);
WIRE 16 -1 (-3850 4525)(-4050 4525);
WIRE 16 -1 (-3850 4300)(-3850 4525);
WIRE 16 -1 (-3850 4300)(-3850 4250);
WIRE 16 -1 (-3550 4300)(-3850 4300);
WIRE 16 -1 (-3850 3950)(-3850 4250);
WIRE 16 -1 (-3550 4250)(-3850 4250);
WIRE 16 -1 (-3850 3950)(-3850 3900);
WIRE 16 -1 (-3550 3950)(-3850 3950);
WIRE 16 -1 (-3850 3900)(-3975 3900);
WIRE 16 -1 (-3550 3900)(-3850 3900);
WIRE 16 -1 (-3975 3900)(-3975 3650);
WIRE 16 -1 (-3975 3650)(-3975 3600);
WIRE 16 -1 (-3550 3650)(-3975 3650);
WIRE 16 -1 (-3975 3600)(-3975 3550);
WIRE 16 -1 (-3550 3600)(-3975 3600);
WIRE 16 -1 (-3550 3550)(-3975 3550);
WIRE 16 -1 (-5250 3175)(-5250 2825);
WIRE 16 -1 (-5250 2825)(-5250 2775);
WIRE 16 -1 (-5925 2825)(-5250 2825);
WIRE 16 -1 (-5250 2775)(-5250 2475);
WIRE 16 -1 (-5925 2775)(-5250 2775);
WIRE 16 -1 (-5250 2475)(-5250 2425);
WIRE 16 -1 (-5925 2475)(-5250 2475);
WIRE 16 -1 (-5250 2425)(-5250 2225);
WIRE 16 -1 (-5925 2425)(-5250 2425);
WIRE 16 -1 (-5250 2225)(-5250 2175);
WIRE 16 -1 (-5925 2225)(-5250 2225);
WIRE 16 -1 (-5250 2175)(-5250 2125);
WIRE 16 -1 (-5925 2175)(-5250 2175);
WIRE 16 -1 (-5250 2125)(-5250 2075);
WIRE 16 -1 (-5925 2125)(-5250 2125);
WIRE 16 -1 (-5250 1875)(-5250 2075);
WIRE 16 -1 (-5925 2075)(-5250 2075);
WIRE 16 -1 (-5250 1875)(-5250 1825);
WIRE 16 -1 (-5925 1875)(-5250 1875);
WIRE 16 -1 (-5250 1825)(-5250 1775);
WIRE 16 -1 (-5925 1825)(-5250 1825);
WIRE 16 -1 (-5250 1775)(-5250 1725);
WIRE 16 -1 (-5925 1775)(-5250 1775);
WIRE 16 -1 (-5250 1725)(-5250 1525);
WIRE 16 -1 (-5925 1725)(-5250 1725);
WIRE 16 -1 (-5250 1525)(-5250 1475);
WIRE 16 -1 (-5925 1525)(-5250 1525);
WIRE 16 -1 (-5250 1475)(-5250 1425);
WIRE 16 -1 (-5925 1475)(-5250 1475);
WIRE 16 -1 (-5250 1425)(-5250 1375);
WIRE 16 -1 (-5925 1425)(-5250 1425);
WIRE 16 -1 (-5925 1375)(-5250 1375);
WIRE 16 -1 (-7225 4525)(-7225 4175);
WIRE 16 -1 (-7225 4175)(-6725 4175);
WIRE 16 -1 (-2300 4500)(-2300 4550);
WIRE 16 -1 (-2300 4450)(-2300 4500);
WIRE 16 -1 (-2750 4500)(-2300 4500);
WIRE 16 -1 (-2300 4400)(-2300 4450);
WIRE 16 -1 (-2750 4450)(-2300 4450);
WIRE 16 -1 (-2300 4150)(-2300 4400);
WIRE 16 -1 (-2750 4400)(-2300 4400);
WIRE 16 -1 (-2300 4100)(-2300 4150);
WIRE 16 -1 (-2750 4150)(-2300 4150);
WIRE 16 -1 (-2300 4050)(-2300 4100);
WIRE 16 -1 (-2750 4100)(-2300 4100);
WIRE 16 -1 (-2300 3800)(-2300 4050);
WIRE 16 -1 (-2750 4050)(-2300 4050);
WIRE 16 -1 (-2300 3750)(-2300 3800);
WIRE 16 -1 (-2750 3800)(-2300 3800);
WIRE 16 -1 (-2300 3700)(-2300 3750);
WIRE 16 -1 (-2750 3750)(-2300 3750);
WIRE 16 -1 (-2300 3450)(-2300 3700);
WIRE 16 -1 (-2750 3700)(-2300 3700);
WIRE 16 -1 (-2300 3400)(-2300 3450);
WIRE 16 -1 (-2750 3450)(-2300 3450);
WIRE 16 -1 (-2300 3350)(-2300 3400);
WIRE 16 -1 (-2750 3400)(-2300 3400);
WIRE 16 -1 (-2300 3100)(-2300 3350);
WIRE 16 -1 (-2750 3350)(-2300 3350);
WIRE 16 -1 (-2300 3050)(-2300 3100);
WIRE 16 -1 (-2750 3100)(-2300 3100);
WIRE 16 -1 (-2300 3000)(-2300 3050);
WIRE 16 -1 (-2750 3050)(-2300 3050);
WIRE 16 -1 (-2300 2750)(-2300 3000);
WIRE 16 -1 (-2750 3000)(-2300 3000);
WIRE 16 -1 (-2300 2700)(-2300 2750);
WIRE 16 -1 (-2750 2750)(-2300 2750);
WIRE 16 -1 (-2300 2650)(-2300 2700);
WIRE 16 -1 (-2750 2700)(-2300 2700);
WIRE 16 -1 (-2300 2400)(-2300 2650);
WIRE 16 -1 (-2750 2650)(-2300 2650);
WIRE 16 -1 (-2300 2350)(-2300 2400);
WIRE 16 -1 (-2750 2400)(-2300 2400);
WIRE 16 -1 (-2300 2300)(-2300 2350);
WIRE 16 -1 (-2750 2350)(-2300 2350);
WIRE 16 -1 (-2300 2050)(-2300 2300);
WIRE 16 -1 (-2750 2300)(-2300 2300);
WIRE 16 -1 (-2300 2000)(-2300 2050);
WIRE 16 -1 (-2750 2050)(-2300 2050);
WIRE 16 -1 (-2300 1950)(-2300 2000);
WIRE 16 -1 (-2750 2000)(-2300 2000);
WIRE 16 -1 (-2750 1950)(-2300 1950);
WIRE 16 -1 (-5150 3650)(-5150 3350);
WIRE 16 -1 (-5150 3350)(-3725 3350);
WIRE 16 -1 (-3725 3100)(-3725 3350);
WIRE 16 -1 (-3550 3350)(-3725 3350);
WIRE 16 -1 (-3725 3050)(-3725 3100);
WIRE 16 -1 (-3550 3100)(-3725 3100);
WIRE 16 -1 (-3725 3000)(-3725 3050);
WIRE 16 -1 (-3550 3050)(-3725 3050);
WIRE 16 -1 (-3725 2750)(-3725 3000);
WIRE 16 -1 (-3550 3000)(-3725 3000);
WIRE 16 -1 (-3725 2700)(-3725 2750);
WIRE 16 -1 (-3550 2750)(-3725 2750);
WIRE 16 -1 (-3725 2650)(-3725 2700);
WIRE 16 -1 (-3550 2700)(-3725 2700);
WIRE 16 -1 (-3725 2400)(-3725 2650);
WIRE 16 -1 (-3550 2650)(-3725 2650);
WIRE 16 -1 (-3725 2350)(-3725 2400);
WIRE 16 -1 (-3550 2400)(-3725 2400);
WIRE 16 -1 (-3725 2300)(-3725 2350);
WIRE 16 -1 (-3550 2350)(-3725 2350);
WIRE 16 -1 (-3725 2050)(-3725 2300);
WIRE 16 -1 (-3550 2300)(-3725 2300);
WIRE 16 -1 (-3725 2000)(-3725 2050);
WIRE 16 -1 (-3550 2050)(-3725 2050);
WIRE 16 -1 (-3725 1950)(-3725 2000);
WIRE 16 -1 (-3550 2000)(-3725 2000);
WIRE 16 -1 (-3725 1700)(-3725 1950);
WIRE 16 -1 (-3550 1950)(-3725 1950);
WIRE 16 -1 (-3725 1650)(-3725 1700);
WIRE 16 -1 (-3550 1700)(-3725 1700);
WIRE 16 -1 (-3725 1600)(-3725 1650);
WIRE 16 -1 (-3550 1650)(-3725 1650);
WIRE 16 -1 (-3725 1350)(-3725 1600);
WIRE 16 -1 (-3550 1600)(-3725 1600);
WIRE 16 -1 (-3725 1300)(-3725 1350);
WIRE 16 -1 (-3550 1350)(-3725 1350);
WIRE 16 -1 (-3725 1250)(-3725 1300);
WIRE 16 -1 (-3550 1300)(-3725 1300);
WIRE 16 -1 (-3550 1250)(-3725 1250);
WIRE 16 -1 (-1900 2625)(-1900 2600);
WIRE 16 -1 (-1900 2600)(-1600 2600);
WIRE 16 -1 (-1900 2550)(-1900 2600);
WIRE 16 -1 (-1600 2600)(-1600 2550);
WIRE 16 -1 (-1300 2600)(-1300 2625);
WIRE 16 -1 (-1000 2600)(-1300 2600);
WIRE 16 -1 (-1300 2550)(-1300 2600);
WIRE 16 -1 (-1000 2550)(-1000 2600);
WIRE 16 -1 (-1600 4125)(-1600 4100);
WIRE 16 -1 (-1300 4100)(-1600 4100);
WIRE 16 -1 (-1600 4050)(-1600 4100);
WIRE 16 -1 (-1300 4050)(-1300 4100);
WIRE 16 -1 (-1900 4075)(-1900 4050);
WIRE 16 -1 (-1900 3275)(-1900 3250);
WIRE 16 -1 (-1600 3250)(-1900 3250);
FORCEPROP 0 LAST VOLTAGE 1.2V
J 0
(-1650 3300);
DISPLAY 1.021277 (-1650 3300);
PAINT SKYBLUE (-1650 3300);
DISPLAY INVISIBLE (-1650 3300);
WIRE 16 -1 (-1900 3200)(-1900 3250);
WIRE 16 -1 (-1600 3250)(-1300 3250);
WIRE 16 -1 (-1600 3200)(-1600 3250);
WIRE 16 -1 (-1300 3250)(-1300 3200);
WIRE 16 -1 (-7950 525)(-7950 500);
WIRE 16 -1 (-7600 525)(-7950 525);
WIRE 16 -1 (-7950 675)(-7950 525);
WIRE 16 -1 (-7600 650)(-7600 525);
WIRE 16 -1 (-7325 4450)(-7325 4275);
WIRE 16 -1 (-7325 4275)(-6725 4275);
WIRE 16 -1 (-1900 3850)(-1900 3825);
WIRE 16 -1 (-1600 3725)(-1600 3750);
WIRE 16 -1 (-1300 3750)(-1600 3750);
WIRE 16 -1 (-1600 3750)(-1600 3850);
WIRE 16 -1 (-1300 3850)(-1300 3750);
WIRE 16 -1 (-2150 1100)(-2150 1000);
WIRE 16 -1 (-2150 1150)(-2150 1100);
WIRE 16 -1 (-2750 1100)(-2150 1100);
WIRE 16 -1 (-2150 1200)(-2150 1150);
WIRE 16 -1 (-2750 1150)(-2150 1150);
WIRE 16 -1 (-2150 1250)(-2150 1200);
WIRE 16 -1 (-2750 1200)(-2150 1200);
WIRE 16 -1 (-2150 1300)(-2150 1250);
WIRE 16 -1 (-2750 1250)(-2150 1250);
WIRE 16 -1 (-2150 1350)(-2150 1300);
WIRE 16 -1 (-2750 1300)(-2150 1300);
WIRE 16 -1 (-2150 1450)(-2150 1350);
WIRE 16 -1 (-2750 1350)(-2150 1350);
WIRE 16 -1 (-2150 1500)(-2150 1450);
WIRE 16 -1 (-2750 1450)(-2150 1450);
WIRE 16 -1 (-2150 1550)(-2150 1500);
WIRE 16 -1 (-2750 1500)(-2150 1500);
WIRE 16 -1 (-2150 1600)(-2150 1550);
WIRE 16 -1 (-2750 1550)(-2150 1550);
WIRE 16 -1 (-2150 1650)(-2150 1600);
WIRE 16 -1 (-2750 1600)(-2150 1600);
WIRE 16 -1 (-2150 1700)(-2150 1650);
WIRE 16 -1 (-2750 1650)(-2150 1650);
WIRE 16 -1 (-2150 1800)(-2150 1700);
WIRE 16 -1 (-2750 1700)(-2150 1700);
WIRE 16 -1 (-2150 1850)(-2150 1800);
WIRE 16 -1 (-2750 1800)(-2150 1800);
WIRE 16 -1 (-2150 1900)(-2150 1850);
WIRE 16 -1 (-2750 1850)(-2150 1850);
WIRE 16 -1 (-2150 1900)(-2150 2150);
WIRE 16 -1 (-2750 1900)(-2150 1900);
WIRE 16 -1 (-2150 2200)(-2150 2150);
WIRE 16 -1 (-2750 2150)(-2150 2150);
WIRE 16 -1 (-2150 2250)(-2150 2200);
WIRE 16 -1 (-2750 2200)(-2150 2200);
WIRE 16 -1 (-2150 2500)(-2150 2250);
WIRE 16 -1 (-2750 2250)(-2150 2250);
WIRE 16 -1 (-2150 2550)(-2150 2500);
WIRE 16 -1 (-2750 2500)(-2150 2500);
WIRE 16 -1 (-2150 2600)(-2150 2550);
WIRE 16 -1 (-2750 2550)(-2150 2550);
WIRE 16 -1 (-2150 2850)(-2150 2600);
WIRE 16 -1 (-2750 2600)(-2150 2600);
WIRE 16 -1 (-2150 2900)(-2150 2850);
WIRE 16 -1 (-2750 2850)(-2150 2850);
WIRE 16 -1 (-2150 2950)(-2150 2900);
WIRE 16 -1 (-2750 2900)(-2150 2900);
WIRE 16 -1 (-2150 3200)(-2150 2950);
WIRE 16 -1 (-2750 2950)(-2150 2950);
WIRE 16 -1 (-2150 3250)(-2150 3200);
WIRE 16 -1 (-2750 3200)(-2150 3200);
WIRE 16 -1 (-2150 3300)(-2150 3250);
WIRE 16 -1 (-2750 3250)(-2150 3250);
WIRE 16 -1 (-2150 3550)(-2150 3300);
WIRE 16 -1 (-2750 3300)(-2150 3300);
WIRE 16 -1 (-2150 3600)(-2150 3550);
WIRE 16 -1 (-2750 3550)(-2150 3550);
WIRE 16 -1 (-2150 3650)(-2150 3600);
WIRE 16 -1 (-2750 3600)(-2150 3600);
WIRE 16 -1 (-2150 3900)(-2150 3650);
WIRE 16 -1 (-2750 3650)(-2150 3650);
WIRE 16 -1 (-2150 3950)(-2150 3900);
WIRE 16 -1 (-2750 3900)(-2150 3900);
WIRE 16 -1 (-2150 4000)(-2150 3950);
WIRE 16 -1 (-2750 3950)(-2150 3950);
WIRE 16 -1 (-2150 4250)(-2150 4000);
WIRE 16 -1 (-2750 4000)(-2150 4000);
WIRE 16 -1 (-2150 4300)(-2150 4250);
WIRE 16 -1 (-2750 4250)(-2150 4250);
WIRE 16 -1 (-2150 4350)(-2150 4300);
WIRE 16 -1 (-2750 4300)(-2150 4300);
WIRE 16 -1 (-2750 4350)(-2150 4350);
WIRE 16 -1 (-3975 1100)(-3975 975);
WIRE 16 -1 (-3975 1150)(-3975 1100);
WIRE 16 -1 (-3550 1100)(-3975 1100);
WIRE 16 -1 (-3975 1200)(-3975 1150);
WIRE 16 -1 (-3550 1150)(-3975 1150);
WIRE 16 -1 (-3975 1450)(-3975 1200);
WIRE 16 -1 (-3550 1200)(-3975 1200);
WIRE 16 -1 (-3975 1500)(-3975 1450);
WIRE 16 -1 (-3550 1450)(-3975 1450);
WIRE 16 -1 (-3975 1550)(-3975 1500);
WIRE 16 -1 (-3550 1500)(-3975 1500);
WIRE 16 -1 (-3975 1800)(-3975 1550);
WIRE 16 -1 (-3550 1550)(-3975 1550);
WIRE 16 -1 (-3975 1850)(-3975 1800);
WIRE 16 -1 (-3550 1800)(-3975 1800);
WIRE 16 -1 (-3975 1900)(-3975 1850);
WIRE 16 -1 (-3550 1850)(-3975 1850);
WIRE 16 -1 (-3975 2150)(-3975 1900);
WIRE 16 -1 (-3550 1900)(-3975 1900);
WIRE 16 -1 (-3975 2200)(-3975 2150);
WIRE 16 -1 (-3550 2150)(-3975 2150);
WIRE 16 -1 (-3975 2250)(-3975 2200);
WIRE 16 -1 (-3550 2200)(-3975 2200);
WIRE 16 -1 (-3975 2500)(-3975 2250);
WIRE 16 -1 (-3550 2250)(-3975 2250);
WIRE 16 -1 (-3975 2550)(-3975 2500);
WIRE 16 -1 (-3550 2500)(-3975 2500);
WIRE 16 -1 (-3975 2600)(-3975 2550);
WIRE 16 -1 (-3550 2550)(-3975 2550);
WIRE 16 -1 (-3975 2600)(-3975 2950);
WIRE 16 -1 (-3550 2600)(-3975 2600);
WIRE 16 -1 (-3975 3200)(-3975 2950);
WIRE 16 -1 (-3550 2950)(-3975 2950);
WIRE 16 -1 (-3975 3250)(-3975 3200);
WIRE 16 -1 (-3550 3200)(-3975 3200);
WIRE 16 -1 (-3975 3300)(-3975 3250);
WIRE 16 -1 (-3550 3250)(-3975 3250);
WIRE 16 -1 (-3550 3300)(-3975 3300);
WIRE 16 -1 (-1900 2225)(-1900 2250);
WIRE 16 -1 (-1900 2250)(-1600 2250);
WIRE 16 -1 (-1900 2350)(-1900 2250);
WIRE 16 -1 (-1600 2350)(-1600 2250);
WIRE 16 -1 (-1300 2250)(-1300 2225);
WIRE 16 -1 (-1000 2250)(-1300 2250);
WIRE 16 -1 (-1300 2350)(-1300 2250);
WIRE 16 -1 (-1000 2350)(-1000 2250);
WIRE 16 -1 (-1900 2875)(-1900 2900);
WIRE 16 -1 (-1600 2900)(-1900 2900);
WIRE 16 -1 (-1900 2900)(-1900 3000);
WIRE 16 -1 (-1300 2900)(-1600 2900);
WIRE 16 -1 (-1600 3000)(-1600 2900);
WIRE 16 -1 (-1300 3000)(-1300 2900);
WIRE 16 -1 (-7150 1925)(-7150 2075);
WIRE 16 -1 (-7150 2075)(-7150 2125);
WIRE 16 -1 (-6725 2075)(-7150 2075);
WIRE 16 -1 (-7150 2125)(-7150 2175);
WIRE 16 -1 (-6725 2125)(-7150 2125);
WIRE 16 -1 (-7150 2225)(-7150 2175);
WIRE 16 -1 (-6725 2175)(-7150 2175);
WIRE 16 -1 (-7150 2425)(-7150 2225);
WIRE 16 -1 (-6725 2225)(-7150 2225);
WIRE 16 -1 (-7150 2475)(-7150 2425);
WIRE 16 -1 (-6725 2425)(-7150 2425);
WIRE 16 -1 (-7150 2525)(-7150 2475);
WIRE 16 -1 (-6725 2475)(-7150 2475);
WIRE 16 -1 (-7150 2575)(-7150 2525);
WIRE 16 -1 (-6725 2525)(-7150 2525);
WIRE 16 -1 (-7150 2775)(-7150 2575);
WIRE 16 -1 (-6725 2575)(-7150 2575);
WIRE 16 -1 (-7150 2825)(-7150 2775);
WIRE 16 -1 (-6725 2775)(-7150 2775);
WIRE 16 -1 (-7150 2875)(-7150 2825);
WIRE 16 -1 (-6725 2825)(-7150 2825);
WIRE 16 -1 (-7150 2925)(-7150 2875);
WIRE 16 -1 (-6725 2875)(-7150 2875);
WIRE 16 -1 (-7150 3125)(-7150 2925);
WIRE 16 -1 (-6725 2925)(-7150 2925);
WIRE 16 -1 (-7150 3175)(-7150 3125);
WIRE 16 -1 (-6725 3125)(-7150 3125);
WIRE 16 -1 (-7150 3225)(-7150 3175);
WIRE 16 -1 (-6725 3175)(-7150 3175);
WIRE 16 -1 (-7150 3275)(-7150 3225);
WIRE 16 -1 (-6725 3225)(-7150 3225);
WIRE 16 -1 (-7150 3475)(-7150 3275);
WIRE 16 -1 (-6725 3275)(-7150 3275);
WIRE 16 -1 (-7150 3525)(-7150 3475);
WIRE 16 -1 (-6725 3475)(-7150 3475);
WIRE 16 -1 (-7150 3575)(-7150 3525);
WIRE 16 -1 (-6725 3525)(-7150 3525);
WIRE 16 -1 (-7150 3625)(-7150 3575);
WIRE 16 -1 (-6725 3575)(-7150 3575);
WIRE 16 -1 (-7150 3825)(-7150 3625);
WIRE 16 -1 (-6725 3625)(-7150 3625);
WIRE 16 -1 (-7150 3875)(-7150 3825);
WIRE 16 -1 (-6725 3825)(-7150 3825);
WIRE 16 -1 (-7150 3925)(-7150 3875);
WIRE 16 -1 (-6725 3875)(-7150 3875);
WIRE 16 -1 (-7150 3975)(-7150 3925);
WIRE 16 -1 (-6725 3925)(-7150 3925);
WIRE 16 -1 (-7150 3975)(-7150 4325);
WIRE 16 -1 (-6725 3975)(-7150 3975);
WIRE 16 -1 (-6725 4325)(-7150 4325);
WIRE 16 -1 (-6950 4425)(-6950 4700);
WIRE 16 -1 (-6950 4375)(-6950 4425);
WIRE 16 -1 (-6725 4425)(-6950 4425);
WIRE 16 -1 (-6950 4075)(-6950 4375);
WIRE 16 -1 (-6725 4375)(-6950 4375);
WIRE 16 -1 (-6950 4025)(-6950 4075);
WIRE 16 -1 (-6725 4075)(-6950 4075);
WIRE 16 -1 (-6950 3725)(-6950 4025);
WIRE 16 -1 (-6725 4025)(-6950 4025);
WIRE 16 -1 (-6950 3675)(-6950 3725);
WIRE 16 -1 (-6725 3725)(-6950 3725);
WIRE 16 -1 (-6950 3375)(-6950 3675);
WIRE 16 -1 (-6725 3675)(-6950 3675);
WIRE 16 -1 (-6950 3325)(-6950 3375);
WIRE 16 -1 (-6725 3375)(-6950 3375);
WIRE 16 -1 (-6950 3025)(-6950 3325);
WIRE 16 -1 (-6725 3325)(-6950 3325);
WIRE 16 -1 (-6950 2975)(-6950 3025);
WIRE 16 -1 (-6725 3025)(-6950 3025);
WIRE 16 -1 (-6950 2675)(-6950 2975);
WIRE 16 -1 (-6725 2975)(-6950 2975);
WIRE 16 -1 (-6950 2625)(-6950 2675);
WIRE 16 -1 (-6725 2675)(-6950 2675);
WIRE 16 -1 (-6950 2325)(-6950 2625);
WIRE 16 -1 (-6725 2625)(-6950 2625);
WIRE 16 -1 (-6950 2275)(-6950 2325);
WIRE 16 -1 (-6725 2325)(-6950 2325);
WIRE 16 -1 (-6950 2275)(-6950 1975);
WIRE 16 -1 (-6725 2275)(-6950 2275);
WIRE 16 -1 (-6950 1975)(-6950 1925);
WIRE 16 -1 (-6950 1975)(-6725 1975);
WIRE 16 -1 (-6950 1925)(-6725 1925);
WIRE 16 -1 (-5525 4425)(-5525 4475);
WIRE 16 -1 (-5525 4375)(-5525 4425);
WIRE 16 -1 (-5925 4425)(-5525 4425);
WIRE 16 -1 (-5525 4325)(-5525 4375);
WIRE 16 -1 (-5925 4375)(-5525 4375);
WIRE 16 -1 (-5925 4325)(-5525 4325);
WIRE 16 -1 (-5500 3725)(-5500 3800);
WIRE 16 -1 (-5500 3675)(-5500 3725);
WIRE 16 -1 (-5925 3725)(-5500 3725);
WIRE 16 -1 (-5500 3625)(-5500 3675);
WIRE 16 -1 (-5925 3675)(-5500 3675);
WIRE 16 -1 (-5925 3625)(-5500 3625);
WIRE 16 -1 (-5125 2225)(-5125 2275);
WIRE 16 -1 (-5125 2325)(-5125 2275);
WIRE 16 -1 (-5925 2275)(-5125 2275);
WIRE 16 -1 (-5125 2325)(-5775 2325);
WIRE 16 -1 (-5775 2525)(-5775 2325);
WIRE 16 -1 (-5925 2325)(-5775 2325);
WIRE 16 -1 (-5775 2575)(-5775 2525);
WIRE 16 -1 (-5925 2525)(-5775 2525);
WIRE 16 -1 (-5775 2875)(-5775 2575);
WIRE 16 -1 (-5925 2575)(-5775 2575);
WIRE 16 -1 (-5775 2925)(-5775 2875);
WIRE 16 -1 (-5925 2875)(-5775 2875);
WIRE 16 -1 (-5775 3125)(-5775 2925);
WIRE 16 -1 (-5925 2925)(-5775 2925);
WIRE 16 -1 (-5775 3175)(-5775 3125);
WIRE 16 -1 (-5925 3125)(-5775 3125);
WIRE 16 -1 (-5775 3225)(-5775 3175);
WIRE 16 -1 (-5925 3175)(-5775 3175);
WIRE 16 -1 (-5775 3275)(-5775 3225);
WIRE 16 -1 (-5925 3225)(-5775 3225);
WIRE 16 -1 (-5775 3325)(-5775 3275);
WIRE 16 -1 (-5925 3275)(-5775 3275);
WIRE 16 -1 (-5775 3375)(-5775 3325);
WIRE 16 -1 (-5925 3325)(-5775 3325);
WIRE 16 -1 (-5775 3475)(-5775 3375);
WIRE 16 -1 (-5925 3375)(-5775 3375);
WIRE 16 -1 (-5775 3525)(-5775 3475);
WIRE 16 -1 (-5925 3475)(-5775 3475);
WIRE 16 -1 (-5775 3575)(-5775 3525);
WIRE 16 -1 (-5925 3525)(-5775 3525);
WIRE 16 -1 (-5775 3575)(-5775 3825);
WIRE 16 -1 (-5925 3575)(-5775 3575);
WIRE 16 -1 (-5775 3875)(-5775 3825);
WIRE 16 -1 (-5925 3825)(-5775 3825);
WIRE 16 -1 (-5775 3925)(-5775 3875);
WIRE 16 -1 (-5925 3875)(-5775 3875);
WIRE 16 -1 (-5775 3975)(-5775 3925);
WIRE 16 -1 (-5925 3925)(-5775 3925);
WIRE 16 -1 (-5775 4025)(-5775 3975);
WIRE 16 -1 (-5925 3975)(-5775 3975);
WIRE 16 -1 (-5775 4075)(-5775 4025);
WIRE 16 -1 (-5925 4025)(-5775 4025);
WIRE 16 -1 (-5775 4175)(-5775 4075);
WIRE 16 -1 (-5925 4075)(-5775 4075);
WIRE 16 -1 (-5775 4225)(-5775 4175);
WIRE 16 -1 (-5925 4175)(-5775 4175);
WIRE 16 -1 (-5775 4225)(-5775 4275);
WIRE 16 -1 (-5925 4225)(-5775 4225);
WIRE 16 -1 (-5925 4275)(-5775 4275);
WIRE 16 -1 (-7125 1550)(-7125 1475);
WIRE 16 -1 (-7125 1550)(-6850 1550);
WIRE 16 -1 (-6850 1525)(-6850 1550);
WIRE 16 -1 (-6850 1550)(-6850 1575);
WIRE 16 -1 (-6850 1575)(-6850 1625);
WIRE 16 -1 (-6725 1575)(-6850 1575);
WIRE 16 -1 (-6850 1525)(-6850 1475);
WIRE 16 -1 (-6725 1525)(-6850 1525);
WIRE 16 -1 (-6850 1425)(-6850 1475);
WIRE 16 -1 (-6725 1475)(-6850 1475);
WIRE 16 -1 (-6850 1625)(-6850 1825);
WIRE 16 -1 (-6725 1625)(-6850 1625);
WIRE 16 -1 (-6850 1825)(-6850 1875);
WIRE 16 -1 (-6725 1825)(-6850 1825);
WIRE 16 -1 (-6850 1375)(-6850 1425);
WIRE 16 -1 (-6725 1425)(-6850 1425);
WIRE 16 -1 (-6850 1275)(-6850 1375);
WIRE 16 -1 (-6725 1375)(-6850 1375);
WIRE 16 -1 (-6725 1875)(-6850 1875);
WIRE 16 -1 (-6850 1225)(-6850 1275);
WIRE 16 -1 (-6725 1275)(-6850 1275);
WIRE 16 -1 (-6850 1175)(-6850 1225);
WIRE 16 -1 (-6725 1225)(-6850 1225);
WIRE 16 -1 (-6850 1125)(-6850 1175);
WIRE 16 -1 (-6725 1175)(-6850 1175);
WIRE 16 -1 (-6725 1125)(-6850 1125);
WIRE 16 -1 (-7925 4225)(-6725 4225);
FORCEPROP 2 LAST SIG_NAME FM_CPU1_VRM_322M_156M_OSC_EN
J 0
(-7900 4235);
DISPLAY 0.617021 (-7900 4235);
PAINT ORANGE (-7900 4235);
WIRE 3 682 (-1350 2850)(-700 2850);
WIRE 3 682 (-700 2850)(-700 3300);
WIRE 3 682 (-1350 2850)(-1350 3300);
WIRE 3 682 (-1350 3300)(-700 3300);
WIRE 3 682 (-2100 2100)(-400 2100);
WIRE 3 682 (-2100 4300)(-2100 2100);
WIRE 3 682 (-400 2100)(-400 4300);
WIRE 3 682 (-400 4300)(-2100 4300);
WIRE 3 682 (-8000 1000)(-8000 425);
WIRE 3 682 (-7225 1000)(-8000 1000);
WIRE 3 682 (-8000 425)(-7225 425);
WIRE 3 682 (-7225 425)(-7225 1000);
WIRE 16 -1 (-7950 875)(-7950 1075);
WIRE 16 -1 (-6725 1075)(-7950 1075);
FORCEPROP 2 LAST SIG_NAME VR_PVCCIOMCP_CPU1_XADDR1
J 0
(-7490 1090);
DISPLAY 0.617021 (-7490 1090);
PAINT ORANGE (-7490 1090);
FORCEPROP 2 LASTPROP $XRERR UNIQUE?
J 0
(-7730 1090);
DISPLAY 0.638298 (-7730 1090);
PAINT MONO (-7730 1090);
DISPLAY INVISIBLE (-7730 1090);
WIRE 16 -1 (-7600 1025)(-7600 850);
WIRE 16 -1 (-7600 1025)(-6725 1025);
FORCEPROP 2 LAST SIG_NAME VR_PVCCMCP_CPU1_XADDR2
J 0
(-7490 1040);
DISPLAY 0.617021 (-7490 1040);
PAINT ORANGE (-7490 1040);
FORCEPROP 2 LASTPROP $XRERR UNIQUE?
J 0
(-7730 1040);
DISPLAY 0.638298 (-7730 1040);
PAINT MONO (-7730 1040);
DISPLAY INVISIBLE (-7730 1040);
WIRE 16 -1 (-5925 1025)(-5150 1025);
FORCEPROP 2 LAST SIG_NAME SVID_DIO1_CPU1_R
J 0
(-5775 1035);
DISPLAY 0.617021 (-5775 1035);
PAINT ORANGE (-5775 1035);
WIRE 16 -1 (-5925 1125)(-5125 1125);
FORCEPROP 2 LAST SIG_NAME PWRGD_PVCCMCP_CPU1
J 0
(-5765 1140);
DISPLAY 0.617021 (-5765 1140);
PAINT ORANGE (-5765 1140);
WIRE 16 -1 (-5925 1075)(-5150 1075);
FORCEPROP 0 LAST SIG_NAME SVID_CLK1_CPU1_R
J 0
(-5775 1085);
DISPLAY 0.617021 (-5775 1085);
PAINT ORANGE (-5775 1085);
WIRE 16 -1 (-5925 1275)(-5150 1275);
FORCEPROP 0 LAST SIG_NAME SVID_CLK0_CPU1_R
J 0
(-5775 1285);
DISPLAY 0.617021 (-5775 1285);
PAINT ORANGE (-5775 1285);
WIRE 16 -1 (-5925 1975)(-5200 1975);
FORCEPROP 2 LAST SIG_NAME SMB_VR_STBY_LVC3_SCL
J 0
(-5815 1990);
DISPLAY 0.617021 (-5815 1990);
PAINT ORANGE (-5815 1990);
WIRE 16 -1 (-5925 1925)(-5200 1925);
FORCEPROP 2 LAST SIG_NAME SMB_VR_STBY_LVC3_SDA
J 0
(-5815 1940);
DISPLAY 0.617021 (-5815 1940);
PAINT ORANGE (-5815 1940);
WIRE 16 -1 (-7625 1725)(-6725 1725);
FORCEPROP 2 LAST SIG_NAME VSENSE_PVCCIOMCP_CPU1_SKT_VRTN
J 0
(-7635 1735);
DISPLAY 0.617021 (-7635 1735);
PAINT ORANGE (-7635 1735);
WIRE 16 -1 (-7625 1775)(-6725 1775);
FORCEPROP 2 LAST SIG_NAME VSENSE_PVCCIOMCP_CPU1_SKT_VSEN
J 0
(-7635 1785);
DISPLAY 0.617021 (-7635 1785);
PAINT ORANGE (-7635 1785);
WIRE 16 -1 (-3550 2900)(-4725 2900);
FORCEPROP 2 LAST SIG_NAME CLK_322M_156M_CPU1_OSC_VRM_DP
J 0
(-4685 2910);
DISPLAY 0.617021 (-4685 2910);
PAINT ORANGE (-4685 2910);
WIRE 16 -1 (-5925 1175)(-5125 1175);
FORCEPROP 2 LAST SIG_NAME FM_PVCCMCP_CPU1_EN
J 0
(-5775 1185);
DISPLAY 0.617021 (-5775 1185);
PAINT ORANGE (-5775 1185);
WIRE 16 -1 (-5925 1225)(-5150 1225);
FORCEPROP 2 LAST SIG_NAME SVID_DIO0_CPU1_R
J 0
(-5775 1235);
DISPLAY 0.617021 (-5775 1235);
PAINT ORANGE (-5775 1235);
WIRE 16 -1 (-5925 1625)(-5200 1625);
FORCEPROP 2 LAST SIG_NAME SVID_ALERT0_CPU1_R_N
J 0
(-5800 1635);
DISPLAY 0.617021 (-5800 1635);
PAINT ORANGE (-5800 1635);
WIRE 16 -1 (-4775 4350)(-3550 4350);
FORCEPROP 2 LAST SIG_NAME VSENSE_P1V8MCP_CPU1_SKT_VSEN
J 0
(-4790 4370);
DISPLAY 0.617021 (-4790 4370);
PAINT ORANGE (-4790 4370);
WIRE 16 -1 (-5925 1575)(-5200 1575);
FORCEPROP 2 LAST SIG_NAME SVID_ALERT1_CPU1_R_N
J 0
(-5800 1585);
DISPLAY 0.617021 (-5800 1585);
PAINT ORANGE (-5800 1585);
WIRE 16 -1 (-5925 3025)(-5150 3025);
FORCEPROP 2 LAST SIG_NAME FM_P1V8MCP_CPU1_EN
J 0
(-5750 3035);
DISPLAY 0.617021 (-5750 3035);
PAINT ORANGE (-5750 3035);
WIRE 16 -1 (-5925 2675)(-5100 2675);
FORCEPROP 2 LAST SIG_NAME FM_PVCCIOMCP_CPU1_EN
J 0
(-5750 2685);
DISPLAY 0.617021 (-5750 2685);
PAINT ORANGE (-5750 2685);
WIRE 3 682 (-5800 2900)(-5800 2850);
WIRE 3 682 (-5750 2900)(-5800 2900);
WIRE 3 682 (-5800 2850)(-5750 2850);
WIRE 3 682 (-5750 2850)(-5750 2900);
WIRE 3 682 (-5800 2550)(-5800 2500);
WIRE 3 682 (-5750 2550)(-5800 2550);
WIRE 3 682 (-5800 2500)(-5750 2500);
WIRE 3 682 (-5750 2500)(-5750 2550);
WIRE 16 -1 (-5925 2625)(-5075 2625);
FORCEPROP 2 LAST SIG_NAME PWRGD_PVCCIOMCP_CPU1
J 0
(-5765 2640);
DISPLAY 0.617021 (-5765 2640);
PAINT ORANGE (-5765 2640);
WIRE 16 -1 (-4775 3400)(-3550 3400);
FORCEPROP 2 LAST SIG_NAME VSENSE_PVCCMCP_CPU1_SKT_VRTN
J 0
(-4765 3420);
DISPLAY 0.617021 (-4765 3420);
PAINT ORANGE (-4765 3420);
WIRE 16 -1 (-4775 3450)(-3550 3450);
FORCEPROP 2 LAST SIG_NAME VSENSE_PVCCMCP_CPU1_SKT_VSEN
J 0
(-4790 3470);
DISPLAY 0.617021 (-4790 3470);
PAINT ORANGE (-4790 3470);
WIRE 3 682 (-3900 3500)(-4050 3500);
WIRE 3 682 (-4050 3500)(-4050 3700);
WIRE 3 682 (-3900 3700)(-3900 3500);
WIRE 3 682 (-3900 3700)(-4050 3700);
WIRE 16 -1 (-4725 4000)(-3550 4000);
FORCEPROP 2 LAST SIG_NAME VSENSE_P1V8MCP_CPU1_SKT_VRTN
J 0
(-4715 4020);
DISPLAY 0.617021 (-4715 4020);
PAINT ORANGE (-4715 4020);
WIRE 16 -1 (-3550 2850)(-4725 2850);
FORCEPROP 2 LAST SIG_NAME CLK_322M_156M_CPU1_OSC_VRM_DN
J 0
(-4685 2860);
DISPLAY 0.617021 (-4685 2860);
PAINT ORANGE (-4685 2860);
WIRE 16 -1 (-5925 2975)(-5125 2975);
FORCEPROP 2 LAST SIG_NAME PWRGD_P1V8MCP_CPU1
J 0
(-5765 2990);
DISPLAY 0.617021 (-5765 2990);
PAINT ORANGE (-5765 2990);
DOT 1 (-3975 2200);
DOT 1 (-6850 1275);
DOT 1 (-7950 525);
DOT 1 (-3725 3750);
DOT 1 (-5775 4025);
DOT 1 (-5775 3875);
DOT 1 (-3975 1200);
DOT 1 (-2150 1650);
DOT 1 (-5775 2875);
DOT 1 (-5775 2925);
DOT 1 (-5775 2525);
DOT 1 (-5775 3125);
DOT 1 (-5775 3175);
DOT 1 (-5250 2475);
DOT 1 (-5250 2425);
DOT 1 (-5775 3275);
DOT 1 (-5775 3225);
DOT 1 (-5250 2225);
DOT 1 (-6950 2275);
DOT 1 (-3725 4400);
DOT 1 (-3975 3650);
DOT 1 (-3850 3900);
DOT 1 (-3850 3950);
DOT 1 (-3725 4100);
DOT 1 (-3725 4050);
DOT 1 (-2150 4000);
DOT 1 (-3725 3000);
DOT 1 (-2300 3750);
DOT 1 (-2300 3800);
DOT 1 (-5250 1475);
DOT 1 (-3975 1100);
DOT 1 (-3975 1850);
DOT 1 (-3975 1900);
DOT 1 (-3975 3250);
DOT 1 (-2150 1600);
DOT 1 (-5250 1525);
DOT 1 (-5775 3325);
DOT 1 (-3975 3200);
DOT 1 (-7150 3925);
DOT 1 (-7150 3975);
DOT 1 (-3975 1150);
DOT 1 (-3975 1500);
DOT 1 (-3975 1450);
DOT 1 (-3975 1550);
DOT 1 (-3975 1800);
DOT 1 (-3725 1300);
DOT 1 (-3725 1350);
DOT 1 (-3725 1600);
DOT 1 (-3725 1700);
DOT 1 (-3725 2000);
DOT 1 (-3725 2050);
DOT 1 (-3975 2250);
DOT 1 (-3975 2550);
DOT 1 (-3975 2600);
DOT 1 (-3975 2950);
DOT 1 (-3725 2300);
DOT 1 (-3725 2400);
DOT 1 (-3725 2350);
DOT 1 (-3725 2650);
DOT 1 (-3725 2700);
DOT 1 (-3725 2750);
DOT 1 (-3725 3050);
DOT 1 (-3725 3100);
DOT 1 (-3725 3350);
DOT 1 (-3725 3800);
DOT 1 (-3725 4150);
DOT 1 (-3725 4450);
DOT 1 (-3725 4500);
DOT 1 (-2150 1450);
DOT 1 (-2150 1500);
DOT 1 (-2150 1550);
DOT 1 (-2150 1700);
DOT 1 (-2150 1800);
DOT 1 (-2150 1900);
DOT 1 (-2150 1850);
DOT 1 (-2150 2150);
DOT 1 (-2150 2200);
DOT 1 (-2150 2250);
DOT 1 (-2300 2400);
DOT 1 (-2300 2350);
DOT 1 (-2150 2550);
DOT 1 (-2150 2500);
DOT 1 (-2300 2650);
DOT 1 (-2300 2700);
DOT 1 (-2300 2750);
DOT 1 (-2150 2600);
DOT 1 (-2300 3050);
DOT 1 (-2300 3000);
DOT 1 (-2150 2850);
DOT 1 (-2150 2950);
DOT 1 (-2300 3100);
DOT 1 (-2150 3300);
DOT 1 (-2150 3250);
DOT 1 (-2300 3350);
DOT 1 (-2300 3400);
DOT 1 (-2300 3450);
DOT 1 (-2150 3550);
DOT 1 (-2300 3700);
DOT 1 (-2150 3650);
DOT 1 (-2150 3600);
DOT 1 (-2300 4050);
DOT 1 (-2150 3950);
DOT 1 (-2150 3900);
DOT 1 (-2300 4100);
DOT 1 (-2300 4150);
DOT 1 (-2150 4250);
DOT 1 (-2300 4400);
DOT 1 (-2300 4450);
DOT 1 (-2300 4500);
DOT 1 (-6850 1525);
DOT 1 (-6950 1975);
DOT 1 (-6850 1625);
DOT 1 (-6850 1825);
DOT 1 (-7150 2075);
DOT 1 (-7150 2125);
DOT 1 (-7150 2175);
DOT 1 (-7150 2225);
DOT 1 (-7150 2425);
DOT 1 (-7150 2525);
DOT 1 (-7150 2475);
DOT 1 (-6950 2325);
DOT 1 (-7150 2775);
DOT 1 (-7150 2575);
DOT 1 (-6950 2625);
DOT 1 (-6950 2675);
DOT 1 (-7150 2825);
DOT 1 (-7150 2875);
DOT 1 (-7150 2925);
DOT 1 (-6950 3025);
DOT 1 (-6950 2975);
DOT 1 (-7150 3175);
DOT 1 (-7150 3125);
DOT 1 (-7150 3225);
DOT 1 (-7150 3275);
DOT 1 (-6950 3325);
DOT 1 (-7150 3475);
DOT 1 (-7150 3525);
DOT 1 (-7150 3575);
DOT 1 (-6950 3375);
DOT 1 (-7150 3825);
DOT 1 (-7150 3625);
DOT 1 (-6950 3675);
DOT 1 (-6950 3725);
DOT 1 (-7150 3875);
DOT 1 (-6950 4025);
DOT 1 (-6950 4075);
DOT 1 (-5250 1425);
DOT 1 (-5250 1725);
DOT 1 (-5250 1775);
DOT 1 (-5250 1875);
DOT 1 (-5250 1825);
DOT 1 (-5775 2325);
DOT 1 (-5775 2575);
DOT 1 (-5250 2075);
DOT 1 (-5250 2175);
DOT 1 (-5250 2125);
DOT 1 (-5125 2275);
DOT 1 (-5250 2775);
DOT 1 (-5250 2825);
DOT 1 (-5775 3375);
DOT 1 (-5775 3475);
DOT 1 (-5775 3525);
DOT 1 (-5775 3575);
DOT 1 (-5775 3825);
DOT 1 (-5775 3925);
DOT 1 (-5775 3975);
DOT 1 (-5775 4075);
DOT 1 (-5500 3725);
DOT 1 (-5500 3675);
DOT 1 (-6950 4375);
DOT 1 (-5775 4175);
DOT 1 (-5775 4225);
DOT 1 (-5525 4375);
DOT 1 (-5525 4425);
DOT 1 (-2150 1350);
DOT 1 (-2150 1300);
DOT 1 (-2150 1250);
DOT 1 (-2150 1200);
DOT 1 (-2150 1150);
DOT 1 (-2150 1100);
DOT 1 (-3975 2500);
DOT 1 (-3975 2150);
DOT 1 (-3850 4250);
DOT 1 (-3850 4300);
DOT 1 (-6850 1425);
DOT 1 (-6850 1225);
DOT 1 (-6850 1175);
DOT 1 (-3975 3600);
DOT 1 (-2300 2300);
DOT 1 (-2300 2050);
DOT 1 (-2300 2000);
DOT 1 (-6950 4425);
DOT 1 (-3725 1650);
DOT 1 (-6850 1475);
DOT 1 (-6850 1575);
DOT 1 (-6850 1550);
DOT 1 (-6850 1375);
DOT 1 (-1900 3250);
DOT 1 (-1600 2900);
DOT 1 (-1900 2900);
DOT 1 (-2150 2900);
DOT 1 (-1600 4100);
DOT 1 (-1600 3750);
DOT 1 (-1600 3250);
DOT 1 (-2150 4300);
DOT 1 (-1300 2600);
DOT 1 (-1300 2250);
DOT 1 (-1900 2600);
DOT 1 (-1900 2250);
DOT 1 (-3725 1950);
DOT 1 (-2150 3200);
FORCENOTE
ROOM=PVCCP_MCP_CPU1
(-2050 3503) 0;
DISPLAY LEFT (-2050 3503);
PAINT PURPLE (-2050 3503);
FORCENOTE
TP FAB3 IMPROVE CPU1_VMCP TRANSIENT PERFORMANCE ADD C4E29 1003
(-2025 3450) 0;
DISPLAY LEFT (-2025 3450);
DISPLAY 0.553191 (-2025 3450);
PAINT RED (-2025 3450);
FORCENOTE
TP FAB4 ADD ATTRIBUTE GROUP=PWR_MCP_CAP 20170508
(-2100 2050) 0;
DISPLAY LEFT (-2100 2050);
DISPLAY 0.638298 (-2100 2050);
PAINT RED (-2100 2050);
FORCENOTE
TP FAB4 ADD ATTRIBUTE GROUP=MCP 20170508
(-3525 775) 0;
DISPLAY LEFT (-3525 775);
DISPLAY 0.510638 (-3525 775);
PAINT RED (-3525 775);
FORCENOTE
TP FAB4 ADD ATTRIBUTE GROUP=MCP 20170508
(-6375 825) 0;
DISPLAY LEFT (-6375 825);
DISPLAY 0.510638 (-6375 825);
PAINT RED (-6375 825);
FORCENOTE
TP FAB4 ADD ATTRIBUTE GROUP=MCP 20170508
(-8025 375) 0;
DISPLAY LEFT (-8025 375);
DISPLAY 0.510638 (-8025 375);
PAINT RED (-8025 375);
FORCENOTE
TP FAB1 CHANGE CONNECTION 0318
(-5100 3675) 0;
DISPLAY LEFT (-5100 3675);
DISPLAY 1.021277 (-5100 3675);
PAINT RED (-5100 3675);
FORCENOTE
TP FAB1 CHANGE CONNECTION 0318
(-5725 2775) 0;
DISPLAY LEFT (-5725 2775);
DISPLAY 1.021277 (-5725 2775);
PAINT RED (-5725 2775);
FORCENOTE
DEBUG ONLY
(-5900 4803) 0;
DISPLAY LEFT (-5900 4803);
DISPLAY 3.851064 (-5900 4803);
PAINT PURPLE (-5900 4803);
FORCENOTE
TP FAB1 CHANGE CONNECTION 0318
(-5725 2500) 0;
DISPLAY LEFT (-5725 2500);
DISPLAY 1.021277 (-5725 2500);
PAINT RED (-5725 2500);
QUIT
